G04 ================== begin FILE IDENTIFICATION RECORD ==================*
G04 Layout Name:  D:/<user>/Wistron_project/16342-2/gbr/16342-2.brd*
G04 Film Name:    DRILL*
G04 File Format:  Gerber RS274X*
G04 File Origin:  Cadence Allegro 16.5-S056*
G04 Origin Date:  Mon Aug 07 11:24:17 2017*
G04 *
G04 Layer:  MANUFACTURING/NCLEGEND-1-8*
G04 Layer:  MANUFACTURING/DRILL SIZE*
G04 Layer:  DRAWING FORMAT/LAYER_PCB_STORY*
G04 Layer:  DRAWING FORMAT/LAYER_DRILL*
G04 Layer:  BOARD GEOMETRY/PANEL_OUTLINE*
G04 *
G04 Offset:    (0.00 0.00)*
G04 Mirror:    No*
G04 Mode:      Positive*
G04 Rotation:  0*
G04 FullContactRelief:  No*
G04 UndefLineWidth:     6.00*
G04 ================== end FILE IDENTIFICATION RECORD ====================*
%FSLAX35Y35*MOIN*%
%IR0*IPPOS*OFA0.00000B0.00000*MIA0B0*SFA1.00000B1.00000*%
%AMMACRO12*
1,1,.006,.005,.005*
20,1,.006,.005,.005,.005,-.005,0.0*
1,1,.006,.005,-.005*
20,1,.006,.005,-.005,-.005,-.005,0.0*
1,1,.006,-.005,-.005*
20,1,.006,-.005,-.005,-.005,.005,0.0*
1,1,.006,-.005,.005*
20,1,.006,-.005,.005,.005,.005,0.0*
1,1,.006,.005,.005*
1,1,.006,-.00158,.00167*
20,1,.006,-.00158,.00167,-.00108,.00217,0.0*
1,1,.006,-.00108,.00217*
20,1,.006,-.00108,.00217,-.0005,.00242,0.0*
1,1,.006,-.0005,.00242*
20,1,.006,-.0005,.00242,.00017,.0025,0.0*
1,1,.006,.00017,.0025*
20,1,.006,.00017,.0025,.001,.00233,0.0*
1,1,.006,.001,.00233*
20,1,.006,.001,.00233,.00158,.00192,0.0*
1,1,.006,.00158,.00192*
20,1,.006,.00158,.00192,.00175,.00142,0.0*
1,1,.006,.00175,.00142*
20,1,.006,.00175,.00142,.00167,.00092,0.0*
1,1,.006,.00167,.00092*
20,1,.006,.00167,.00092,.00133,.0005,0.0*
1,1,.006,.00133,.0005*
20,1,.006,.00133,.0005,-.00033,-.00033,0.0*
1,1,.006,-.00033,-.00033*
20,1,.006,-.00033,-.00033,-.00108,-.00092,0.0*
1,1,.006,-.00108,-.00092*
20,1,.006,-.00108,-.00092,-.00158,-.00175,0.0*
1,1,.006,-.00158,-.00175*
20,1,.006,-.00158,-.00175,-.00175,-.0025,0.0*
1,1,.006,-.00175,-.0025*
20,1,.006,-.00175,-.0025,.00175,-.0025,0.0*
1,1,.006,.00175,-.0025*
%
%ADD12MACRO12*%
%AMMACRO29*
1,1,.006,.002899,-.007*
20,1,.006,.002899,-.007,-.002899,-.007,0.0*
1,1,.006,-.002899,-.007*
20,1,.006,-.002899,-.007,-.007,-.002899,0.0*
1,1,.006,-.007,-.002899*
20,1,.006,-.007,-.002899,-.007,.002899,0.0*
1,1,.006,-.007,.002899*
20,1,.006,-.007,.002899,-.002899,.007,0.0*
1,1,.006,-.002899,.007*
20,1,.006,-.002899,.007,.002899,.007,0.0*
1,1,.006,.002899,.007*
20,1,.006,.002899,.007,.007,.002899,0.0*
1,1,.006,.007,.002899*
20,1,.006,.007,.002899,.007,-.002899,0.0*
1,1,.006,.007,-.002899*
20,1,.006,.007,-.002899,.002899,-.007,0.0*
1,1,.006,.002899,-.007*
1,1,.006,-.00257,-.00245*
20,1,.006,-.00257,-.00245,-.00187,-.00303,0.0*
1,1,.006,-.00187,-.00303*
20,1,.006,-.00187,-.00303,-.00105,-.00338,0.0*
1,1,.006,-.00105,-.00338*
20,1,.006,-.00105,-.00338,0.0,-.0035,0.0*
1,1,.006,0.0,-.0035*
20,1,.006,0.0,-.0035,.00105,-.00327,0.0*
1,1,.006,.00105,-.00327*
20,1,.006,.00105,-.00327,.00187,-.0028,0.0*
1,1,.006,.00187,-.0028*
20,1,.006,.00187,-.0028,.00245,-.00198,0.0*
1,1,.006,.00245,-.00198*
20,1,.006,.00245,-.00198,.00257,-.00105,0.0*
1,1,.006,.00257,-.00105*
20,1,.006,.00257,-.00105,.00233,-.00012,0.0*
1,1,.006,.00233,-.00012*
20,1,.006,.00233,-.00012,.00175,.00047,0.0*
1,1,.006,.00175,.00047*
20,1,.006,.00175,.00047,.00093,.00093,0.0*
1,1,.006,.00093,.00093*
20,1,.006,.00093,.00093,.00012,.00105,0.0*
1,1,.006,.00012,.00105*
20,1,.006,.00012,.00105,-.0007,.00093,0.0*
1,1,.006,-.0007,.00093*
20,1,.006,-.0007,.00093,-.00175,.00047,0.0*
1,1,.006,-.00175,.00047*
20,1,.006,-.00175,.00047,-.0014,.0035,0.0*
1,1,.006,-.0014,.0035*
20,1,.006,-.0014,.0035,.00175,.0035,0.0*
1,1,.006,.00175,.0035*
%
%ADD29MACRO29*%
%AMMACRO20*
1,1,.006,.004,0.0*
20,1,.006,.004,0.0,-.004,0.0,0.0*
1,1,.006,-.004,0.0*
1,1,.006,0.0,.004*
20,1,.006,0.0,.004,0.0,-.004,0.0*
1,1,.006,0.0,-.004*
1,1,.006,.002,0.0*
20,1,.006,.002,0.0,.002,.004,0.0*
1,1,.006,.002,.004*
20,1,.006,.002,.004,.0012,.0032,0.0*
1,1,.006,.0012,.0032*
1,1,.006,.0012,0.0*
20,1,.006,.0012,0.0,.0028,0.0,0.0*
1,1,.006,.0028,0.0*
%
%ADD20MACRO20*%
%AMMACRO21*
1,1,.006,.01173,.01333*
20,1,.006,.01173,.01333,.00853,.01493,0.0*
1,1,.006,.00853,.01493*
20,1,.006,.00853,.01493,.0048,.016,0.0*
1,1,.006,.0048,.016*
20,1,.006,.0048,.016,.00053,.016,0.0*
1,1,.006,.00053,.016*
20,1,.006,.00053,.016,-.00427,.0144,0.0*
1,1,.006,-.00427,.0144*
20,1,.006,-.00427,.0144,-.008,.01173,0.0*
1,1,.006,-.008,.01173*
20,1,.006,-.008,.01173,-.01067,.00853,0.0*
1,1,.006,-.01067,.00853*
20,1,.006,-.01067,.00853,-.0128,.0032,0.0*
1,1,.006,-.0128,.0032*
20,1,.006,-.0128,.0032,-.01333,-.0016,0.0*
1,1,.006,-.01333,-.0016*
20,1,.006,-.01333,-.0016,-.01227,-.0064,0.0*
1,1,.006,-.01227,-.0064*
20,1,.006,-.01227,-.0064,-.01067,-.0096,0.0*
1,1,.006,-.01067,-.0096*
20,1,.006,-.01067,-.0096,-.00747,-.0128,0.0*
1,1,.006,-.00747,-.0128*
20,1,.006,-.00747,-.0128,-.00373,-.01493,0.0*
1,1,.006,-.00373,-.01493*
20,1,.006,-.00373,-.01493,0.0,-.016,0.0*
1,1,.006,0.0,-.016*
20,1,.006,0.0,-.016,.00373,-.016,0.0*
1,1,.006,.00373,-.016*
20,1,.006,.00373,-.016,.00747,-.01493,0.0*
1,1,.006,.00747,-.01493*
20,1,.006,.00747,-.01493,.01067,-.01333,0.0*
1,1,.006,.01067,-.01333*
20,1,.006,.01067,-.01333,.01333,-.0112,0.0*
1,1,.006,.01333,-.0112*
%
%ADD21MACRO21*%
%AMMACRO18*
1,1,.006,-.04767,-.065*
20,1,.006,-.04767,-.065,-.04767,.065,0.0*
1,1,.006,-.04767,.065*
1,1,.006,.03467,.065*
20,1,.006,.03467,.065,-.04767,-.01517,0.0*
1,1,.006,-.04767,-.01517*
1,1,.006,.04767,-.065*
20,1,.006,.04767,-.065,-.01083,.02166,0.0*
1,1,.006,-.01083,.02166*
%
%ADD18MACRO18*%
%AMMACRO27*
1,1,.006,-.01247,-.017*
20,1,.006,-.01247,-.017,-.01247,.017,0.0*
1,1,.006,-.01247,.017*
20,1,.006,-.01247,.017,-.00113,.017,0.0*
1,1,.006,-.00113,.017*
20,1,.006,-.00113,.017,.0034,.0153,0.0*
1,1,.006,.0034,.0153*
20,1,.006,.0034,.0153,.0068,.01303,0.0*
1,1,.006,.0068,.01303*
20,1,.006,.0068,.01303,.00963,.00963,0.0*
1,1,.006,.00963,.00963*
20,1,.006,.00963,.00963,.0119,.00567,0.0*
1,1,.006,.0119,.00567*
20,1,.006,.0119,.00567,.01247,0.0,0.0*
1,1,.006,.01247,0.0*
20,1,.006,.01247,0.0,.0119,-.00567,0.0*
1,1,.006,.0119,-.00567*
20,1,.006,.0119,-.00567,.00963,-.00963,0.0*
1,1,.006,.00963,-.00963*
20,1,.006,.00963,-.00963,.0068,-.01303,0.0*
1,1,.006,.0068,-.01303*
20,1,.006,.0068,-.01303,.0034,-.0153,0.0*
1,1,.006,.0034,-.0153*
20,1,.006,.0034,-.0153,-.00113,-.017,0.0*
1,1,.006,-.00113,-.017*
20,1,.006,-.00113,-.017,-.01247,-.017,0.0*
1,1,.006,-.01247,-.017*
%
%ADD27MACRO27*%
%AMMACRO33*
1,1,.006,.01467,-.022*
20,1,.006,.01467,-.022,-.01467,-.022,0.0*
1,1,.006,-.01467,-.022*
20,1,.006,-.01467,-.022,-.01467,.022,0.0*
1,1,.006,-.01467,.022*
20,1,.006,-.01467,.022,.01467,.022,0.0*
1,1,.006,.01467,.022*
1,1,.006,.00293,.00073*
20,1,.006,.00293,.00073,-.01467,.00073,0.0*
1,1,.006,-.01467,.00073*
%
%ADD33MACRO33*%
%AMMACRO28*
1,1,.006,.007085,0.0*
20,1,.006,.007085,0.0,0.0,-.007085,0.0*
1,1,.006,0.0,-.007085*
20,1,.006,0.0,-.007085,-.007085,0.0,0.0*
1,1,.006,-.007085,0.0*
20,1,.006,-.007085,0.0,0.0,.007085,0.0*
1,1,.006,0.0,.007085*
20,1,.006,0.0,.007085,.007085,0.0,0.0*
1,1,.006,.007085,0.0*
1,1,.006,-.00224,-.00059*
20,1,.006,-.00224,-.00059,-.00142,.00024,0.0*
1,1,.006,-.00142,.00024*
20,1,.006,-.00142,.00024,-.00071,.00071,0.0*
1,1,.006,-.00071,.00071*
20,1,.006,-.00071,.00071,.00024,.00094,0.0*
1,1,.006,.00024,.00094*
20,1,.006,.00024,.00094,.00106,.00071,0.0*
1,1,.006,.00106,.00071*
20,1,.006,.00106,.00071,.00165,.00024,0.0*
1,1,.006,.00165,.00024*
20,1,.006,.00165,.00024,.00212,-.00047,0.0*
1,1,.006,.00212,-.00047*
20,1,.006,.00212,-.00047,.00224,-.0013,0.0*
1,1,.006,.00224,-.0013*
20,1,.006,.00224,-.0013,.00212,-.00201,0.0*
1,1,.006,.00212,-.00201*
20,1,.006,.00212,-.00201,.00165,-.00271,0.0*
1,1,.006,.00165,-.00271*
20,1,.006,.00165,-.00271,.00094,-.0033,0.0*
1,1,.006,.00094,-.0033*
20,1,.006,.00094,-.0033,.00012,-.00354,0.0*
1,1,.006,.00012,-.00354*
20,1,.006,.00012,-.00354,-.00083,-.0033,0.0*
1,1,.006,-.00083,-.0033*
20,1,.006,-.00083,-.0033,-.00165,-.0026,0.0*
1,1,.006,-.00165,-.0026*
20,1,.006,-.00165,-.0026,-.00212,-.00153,0.0*
1,1,.006,-.00212,-.00153*
20,1,.006,-.00212,-.00153,-.00224,-.00035,0.0*
1,1,.006,-.00224,-.00035*
20,1,.006,-.00224,-.00035,-.00201,.00118,0.0*
1,1,.006,-.00201,.00118*
20,1,.006,-.00201,.00118,-.00165,.00201,0.0*
1,1,.006,-.00165,.00201*
20,1,.006,-.00165,.00201,-.00106,.00283,0.0*
1,1,.006,-.00106,.00283*
20,1,.006,-.00106,.00283,-.00024,.00342,0.0*
1,1,.006,-.00024,.00342*
20,1,.006,-.00024,.00342,.00059,.00354,0.0*
1,1,.006,.00059,.00354*
20,1,.006,.00059,.00354,.00142,.0033,0.0*
1,1,.006,.00142,.0033*
20,1,.006,.00142,.0033,.00201,.00271,0.0*
1,1,.006,.00201,.00271*
%
%ADD28MACRO28*%
%AMMACRO16*
1,1,.006,-.06584,-.079*
20,1,.006,-.06584,-.079,0.0,.079,0.0*
1,1,.006,0.0,.079*
20,1,.006,0.0,.079,.06584,-.079,0.0*
1,1,.006,.06584,-.079*
1,1,.006,.04213,-.0237*
20,1,.006,.04213,-.0237,-.04214,-.0237,0.0*
1,1,.006,-.04214,-.0237*
%
%ADD16MACRO16*%
%AMMACRO34*
1,1,.006,.0063,0.0*
20,1,.006,.0063,0.0,.0273,0.0,0.0*
1,1,.006,.0273,0.0*
20,1,.006,.0273,0.0,.0273,-.0189,0.0*
1,1,.006,.0273,-.0189*
20,1,.006,.0273,-.0189,.021,-.0252,0.0*
1,1,.006,.021,-.0252*
20,1,.006,.021,-.0252,.01365,-.0294,0.0*
1,1,.006,.01365,-.0294*
20,1,.006,.01365,-.0294,.00315,-.0315,0.0*
1,1,.006,.00315,-.0315*
20,1,.006,.00315,-.0315,-.00735,-.0294,0.0*
1,1,.006,-.00735,-.0294*
20,1,.006,-.00735,-.0294,-.0147,-.0252,0.0*
1,1,.006,-.0147,-.0252*
20,1,.006,-.0147,-.0252,-.021,-.0189,0.0*
1,1,.006,-.021,-.0189*
20,1,.006,-.021,-.0189,-.0252,-.01155,0.0*
1,1,.006,-.0252,-.01155*
20,1,.006,-.0252,-.01155,-.0273,-.00315,0.0*
1,1,.006,-.0273,-.00315*
20,1,.006,-.0273,-.00315,-.0273,.0042,0.0*
1,1,.006,-.0273,.0042*
20,1,.006,-.0273,.0042,-.0252,.0105,0.0*
1,1,.006,-.0252,.0105*
20,1,.006,-.0252,.0105,-.021,.01785,0.0*
1,1,.006,-.021,.01785*
20,1,.006,-.021,.01785,-.0147,.02415,0.0*
1,1,.006,-.0147,.02415*
20,1,.006,-.0147,.02415,-.0084,.02835,0.0*
1,1,.006,-.0084,.02835*
20,1,.006,-.0084,.02835,0.0,.0315,0.0*
1,1,.006,0.0,.0315*
20,1,.006,0.0,.0315,.00735,.0315,0.0*
1,1,.006,.00735,.0315*
20,1,.006,.00735,.0315,.01575,.0294,0.0*
1,1,.006,.01575,.0294*
20,1,.006,.01575,.0294,.02205,.0252,0.0*
1,1,.006,.02205,.0252*
%
%ADD34MACRO34*%
%AMMACRO22*
1,1,.006,.0224,.0056*
20,1,.006,.0224,.0056,.0336,.014,0.0*
1,1,.006,.0336,.014*
20,1,.006,.0336,.014,.042,.028,0.0*
1,1,.006,.042,.028*
20,1,.006,.042,.028,.0476,.0476,0.0*
1,1,.006,.0476,.0476*
20,1,.006,.0476,.0476,.042,.0644,0.0*
1,1,.006,.042,.0644*
20,1,.006,.042,.0644,.0308,.0756,0.0*
1,1,.006,.0308,.0756*
20,1,.006,.0308,.0756,.0112,.084,0.0*
1,1,.006,.0112,.084*
20,1,.006,.0112,.084,-.0644,.084,0.0*
1,1,.006,-.0644,.084*
20,1,.006,-.0644,.084,-.0644,-.084,0.0*
1,1,.006,-.0644,-.084*
20,1,.006,-.0644,-.084,.028,-.084,0.0*
1,1,.006,.028,-.084*
20,1,.006,.028,-.084,.0476,-.0728,0.0*
1,1,.006,.0476,-.0728*
20,1,.006,.0476,-.0728,.0588,-.056,0.0*
1,1,.006,.0588,-.056*
20,1,.006,.0588,-.056,.0644,-.0364,0.0*
1,1,.006,.0644,-.0364*
20,1,.006,.0644,-.0364,.0588,-.0168,0.0*
1,1,.006,.0588,-.0168*
20,1,.006,.0588,-.0168,.042,0.0,0.0*
1,1,.006,.042,0.0*
20,1,.006,.042,0.0,.0224,.0056,0.0*
1,1,.006,.0224,.0056*
20,1,.006,.0224,.0056,-.0644,.0056,0.0*
1,1,.006,-.0644,.0056*
%
%ADD22MACRO22*%
%AMMACRO26*
1,1,.006,-.0152,-.024*
20,1,.006,-.0152,-.024,-.0152,.024,0.0*
1,1,.006,-.0152,.024*
20,1,.006,-.0152,.024,.0152,.024,0.0*
1,1,.006,.0152,.024*
1,1,.006,.004,.0008*
20,1,.006,.004,.0008,-.0152,.0008,0.0*
1,1,.006,-.0152,.0008*
%
%ADD26MACRO26*%
%AMMACRO31*
1,1,.006,-.0188,.047*
20,1,.006,-.0188,.047,.0188,.047,0.0*
1,1,.006,.0188,.047*
1,1,.006,0.0,.047*
20,1,.006,0.0,.047,0.0,-.047,0.0*
1,1,.006,0.0,-.047*
1,1,.006,-.0188,-.047*
20,1,.006,-.0188,-.047,.0188,-.047,0.0*
1,1,.006,.0188,-.047*
%
%ADD31MACRO31*%
%AMMACRO13*
1,1,.006,-.0301,-.043*
20,1,.006,-.0301,-.043,-.0301,.043,0.0*
1,1,.006,-.0301,.043*
1,1,.006,.0301,.043*
20,1,.006,.0301,.043,.0301,-.043,0.0*
1,1,.006,.0301,-.043*
1,1,.006,.0301,0.0*
20,1,.006,.0301,0.0,-.0301,0.0,0.0*
1,1,.006,-.0301,0.0*
%
%ADD13MACRO13*%
%AMMACRO30*
1,1,.006,-.03233,-.0291*
20,1,.006,-.03233,-.0291,-.02425,-.0388,0.0*
1,1,.006,-.02425,-.0388*
20,1,.006,-.02425,-.0388,-.01455,-.04527,0.0*
1,1,.006,-.01455,-.04527*
20,1,.006,-.01455,-.04527,-.00323,-.0485,0.0*
1,1,.006,-.00323,-.0485*
20,1,.006,-.00323,-.0485,.0097,-.04527,0.0*
1,1,.006,.0097,-.04527*
20,1,.006,.0097,-.04527,.0194,-.0388,0.0*
1,1,.006,.0194,-.0388*
20,1,.006,.0194,-.0388,.0291,-.0291,0.0*
1,1,.006,.0291,-.0291*
20,1,.006,.0291,-.0291,.03233,-.01617,0.0*
1,1,.006,.03233,-.01617*
20,1,.006,.03233,-.01617,.03233,.0485,0.0*
1,1,.006,.03233,.0485*
%
%ADD30MACRO30*%
%AMMACRO19*
1,1,.006,.005,0.0*
20,1,.006,.005,0.0,.0025,.00433,0.0*
1,1,.006,.0025,.00433*
20,1,.006,.0025,.00433,-.0025,.00433,0.0*
1,1,.006,-.0025,.00433*
20,1,.006,-.0025,.00433,-.005,0.0,0.0*
1,1,.006,-.005,0.0*
20,1,.006,-.005,0.0,-.0025,-.00433,0.0*
1,1,.006,-.0025,-.00433*
20,1,.006,-.0025,-.00433,.0025,-.00433,0.0*
1,1,.006,.0025,-.00433*
20,1,.006,.0025,-.00433,.005,0.0,0.0*
1,1,.006,.005,0.0*
1,1,.006,-.00183,-.0015*
20,1,.006,-.00183,-.0015,-.00133,-.00208,0.0*
1,1,.006,-.00133,-.00208*
20,1,.006,-.00133,-.00208,-.00067,-.00242,0.0*
1,1,.006,-.00067,-.00242*
20,1,.006,-.00067,-.00242,.00008,-.0025,0.0*
1,1,.006,.00008,-.0025*
20,1,.006,.00008,-.0025,.00075,-.00242,0.0*
1,1,.006,.00075,-.00242*
20,1,.006,.00075,-.00242,.00142,-.002,0.0*
1,1,.006,.00142,-.002*
20,1,.006,.00142,-.002,.00183,-.0015,0.0*
1,1,.006,.00183,-.0015*
20,1,.006,.00183,-.0015,.00192,-.001,0.0*
1,1,.006,.00192,-.001*
20,1,.006,.00192,-.001,.00175,-.00042,0.0*
1,1,.006,.00175,-.00042*
20,1,.006,.00175,-.00042,.00117,0.0,0.0*
1,1,.006,.00117,0.0*
20,1,.006,.00117,0.0,.00058,.00017,0.0*
1,1,.006,.00058,.00017*
20,1,.006,.00058,.00017,-.00017,.00017,0.0*
1,1,.006,-.00017,.00017*
1,1,.006,.00058,.00017*
20,1,.006,.00058,.00017,.00108,.00042,0.0*
1,1,.006,.00108,.00042*
20,1,.006,.00108,.00042,.0015,.00083,0.0*
1,1,.006,.0015,.00083*
20,1,.006,.0015,.00083,.00167,.00133,0.0*
1,1,.006,.00167,.00133*
20,1,.006,.00167,.00133,.0015,.00183,0.0*
1,1,.006,.0015,.00183*
20,1,.006,.0015,.00183,.00108,.00225,0.0*
1,1,.006,.00108,.00225*
20,1,.006,.00108,.00225,.00033,.0025,0.0*
1,1,.006,.00033,.0025*
20,1,.006,.00033,.0025,-.00042,.00242,0.0*
1,1,.006,-.00042,.00242*
20,1,.006,-.00042,.00242,-.00117,.00208,0.0*
1,1,.006,-.00117,.00208*
%
%ADD19MACRO19*%
%AMMACRO25*
1,1,.006,-.016,-.012*
20,1,.006,-.016,-.012,-.016,.012,0.0*
1,1,.006,-.016,.012*
20,1,.006,-.016,.012,-.015757,.014778,0.0*
1,1,.006,-.015757,.014778*
20,1,.006,-.015757,.014778,-.015035,.017472,0.0*
1,1,.006,-.015035,.017472*
20,1,.006,-.015035,.017472,-.013856,.02,0.0*
1,1,.006,-.013856,.02*
20,1,.006,-.013856,.02,-.012257,.022285,0.0*
1,1,.006,-.012257,.022285*
20,1,.006,-.012257,.022285,-.010285,.024257,0.0*
1,1,.006,-.010285,.024257*
20,1,.006,-.010285,.024257,-.008,.025856,0.0*
1,1,.006,-.008,.025856*
20,1,.006,-.008,.025856,-.005472,.027035,0.0*
1,1,.006,-.005472,.027035*
20,1,.006,-.005472,.027035,-.002778,.027757,0.0*
1,1,.006,-.002778,.027757*
20,1,.006,-.002778,.027757,0.0,.028,0.0*
1,1,.006,0.0,.028*
20,1,.006,0.0,.028,.002778,.027757,0.0*
1,1,.006,.002778,.027757*
20,1,.006,.002778,.027757,.005472,.027035,0.0*
1,1,.006,.005472,.027035*
20,1,.006,.005472,.027035,.008,.025856,0.0*
1,1,.006,.008,.025856*
20,1,.006,.008,.025856,.010285,.024257,0.0*
1,1,.006,.010285,.024257*
20,1,.006,.010285,.024257,.012257,.022285,0.0*
1,1,.006,.012257,.022285*
20,1,.006,.012257,.022285,.013856,.02,0.0*
1,1,.006,.013856,.02*
20,1,.006,.013856,.02,.015035,.017472,0.0*
1,1,.006,.015035,.017472*
20,1,.006,.015035,.017472,.015757,.014778,0.0*
1,1,.006,.015757,.014778*
20,1,.006,.015757,.014778,.016,.012,0.0*
1,1,.006,.016,.012*
20,1,.006,.016,.012,.016,-.012,0.0*
1,1,.006,.016,-.012*
20,1,.006,.016,-.012,.015757,-.014778,0.0*
1,1,.006,.015757,-.014778*
20,1,.006,.015757,-.014778,.015035,-.017472,0.0*
1,1,.006,.015035,-.017472*
20,1,.006,.015035,-.017472,.013856,-.02,0.0*
1,1,.006,.013856,-.02*
20,1,.006,.013856,-.02,.012257,-.022285,0.0*
1,1,.006,.012257,-.022285*
20,1,.006,.012257,-.022285,.010285,-.024257,0.0*
1,1,.006,.010285,-.024257*
20,1,.006,.010285,-.024257,.008,-.025856,0.0*
1,1,.006,.008,-.025856*
20,1,.006,.008,-.025856,.005472,-.027035,0.0*
1,1,.006,.005472,-.027035*
20,1,.006,.005472,-.027035,.002778,-.027757,0.0*
1,1,.006,.002778,-.027757*
20,1,.006,.002778,-.027757,0.0,-.028,0.0*
1,1,.006,0.0,-.028*
20,1,.006,0.0,-.028,-.002778,-.027757,0.0*
1,1,.006,-.002778,-.027757*
20,1,.006,-.002778,-.027757,-.005472,-.027035,0.0*
1,1,.006,-.005472,-.027035*
20,1,.006,-.005472,-.027035,-.008,-.025856,0.0*
1,1,.006,-.008,-.025856*
20,1,.006,-.008,-.025856,-.010285,-.024257,0.0*
1,1,.006,-.010285,-.024257*
20,1,.006,-.010285,-.024257,-.012257,-.022285,0.0*
1,1,.006,-.012257,-.022285*
20,1,.006,-.012257,-.022285,-.013856,-.02,0.0*
1,1,.006,-.013856,-.02*
20,1,.006,-.013856,-.02,-.015035,-.017472,0.0*
1,1,.006,-.015035,-.017472*
20,1,.006,-.015035,-.017472,-.015757,-.014778,0.0*
1,1,.006,-.015757,-.014778*
20,1,.006,-.015757,-.014778,-.016,-.012,0.0*
1,1,.006,-.016,-.012*
1,1,.006,-.008,-.008*
20,1,.006,-.008,-.008,-.01013,-.00773,0.0*
1,1,.006,-.01013,-.00773*
20,1,.006,-.01013,-.00773,-.012,-.00667,0.0*
1,1,.006,-.012,-.00667*
20,1,.006,-.012,-.00667,-.0136,-.00507,0.0*
1,1,.006,-.0136,-.00507*
20,1,.006,-.0136,-.00507,-.01467,-.0032,0.0*
1,1,.006,-.01467,-.0032*
20,1,.006,-.01467,-.0032,-.0152,-.00107,0.0*
1,1,.006,-.0152,-.00107*
20,1,.006,-.0152,-.00107,-.0152,.00107,0.0*
1,1,.006,-.0152,.00107*
20,1,.006,-.0152,.00107,-.01467,.0032,0.0*
1,1,.006,-.01467,.0032*
20,1,.006,-.01467,.0032,-.0136,.00507,0.0*
1,1,.006,-.0136,.00507*
20,1,.006,-.0136,.00507,-.012,.00667,0.0*
1,1,.006,-.012,.00667*
20,1,.006,-.012,.00667,-.01013,.00773,0.0*
1,1,.006,-.01013,.00773*
20,1,.006,-.01013,.00773,-.008,.008,0.0*
1,1,.006,-.008,.008*
20,1,.006,-.008,.008,-.00587,.00773,0.0*
1,1,.006,-.00587,.00773*
20,1,.006,-.00587,.00773,-.004,.00667,0.0*
1,1,.006,-.004,.00667*
20,1,.006,-.004,.00667,-.0024,.00507,0.0*
1,1,.006,-.0024,.00507*
20,1,.006,-.0024,.00507,-.00133,.0032,0.0*
1,1,.006,-.00133,.0032*
20,1,.006,-.00133,.0032,-.0008,.00107,0.0*
1,1,.006,-.0008,.00107*
20,1,.006,-.0008,.00107,-.0008,-.00107,0.0*
1,1,.006,-.0008,-.00107*
20,1,.006,-.0008,-.00107,-.00133,-.0032,0.0*
1,1,.006,-.00133,-.0032*
20,1,.006,-.00133,-.0032,-.0024,-.00507,0.0*
1,1,.006,-.0024,-.00507*
20,1,.006,-.0024,-.00507,-.004,-.00667,0.0*
1,1,.006,-.004,-.00667*
20,1,.006,-.004,-.00667,-.00587,-.00773,0.0*
1,1,.006,-.00587,-.00773*
20,1,.006,-.00587,-.00773,-.008,-.008,0.0*
1,1,.006,-.008,-.008*
1,1,.006,.00134,-.008*
20,1,.006,.00134,-.008,.00801,.008,0.0*
1,1,.006,.00801,.008*
20,1,.006,.00801,.008,.01468,-.008,0.0*
1,1,.006,.01468,-.008*
1,1,.006,.01228,-.0024*
20,1,.006,.01228,-.0024,.00374,-.0024,0.0*
1,1,.006,.00374,-.0024*
%
%ADD25MACRO25*%
%AMMACRO24*
1,1,.006,-.016,-.0255*
20,1,.006,-.016,-.0255,-.016,.0255,0.0*
1,1,.006,-.016,.0255*
20,1,.006,-.016,.0255,-.015757,.028278,0.0*
1,1,.006,-.015757,.028278*
20,1,.006,-.015757,.028278,-.015035,.030972,0.0*
1,1,.006,-.015035,.030972*
20,1,.006,-.015035,.030972,-.013856,.0335,0.0*
1,1,.006,-.013856,.0335*
20,1,.006,-.013856,.0335,-.012257,.035785,0.0*
1,1,.006,-.012257,.035785*
20,1,.006,-.012257,.035785,-.010285,.037757,0.0*
1,1,.006,-.010285,.037757*
20,1,.006,-.010285,.037757,-.008,.039356,0.0*
1,1,.006,-.008,.039356*
20,1,.006,-.008,.039356,-.005472,.040535,0.0*
1,1,.006,-.005472,.040535*
20,1,.006,-.005472,.040535,-.002778,.041257,0.0*
1,1,.006,-.002778,.041257*
20,1,.006,-.002778,.041257,0.0,.0415,0.0*
1,1,.006,0.0,.0415*
20,1,.006,0.0,.0415,.002778,.041257,0.0*
1,1,.006,.002778,.041257*
20,1,.006,.002778,.041257,.005472,.040535,0.0*
1,1,.006,.005472,.040535*
20,1,.006,.005472,.040535,.008,.039356,0.0*
1,1,.006,.008,.039356*
20,1,.006,.008,.039356,.010285,.037757,0.0*
1,1,.006,.010285,.037757*
20,1,.006,.010285,.037757,.012257,.035785,0.0*
1,1,.006,.012257,.035785*
20,1,.006,.012257,.035785,.013856,.0335,0.0*
1,1,.006,.013856,.0335*
20,1,.006,.013856,.0335,.015035,.030972,0.0*
1,1,.006,.015035,.030972*
20,1,.006,.015035,.030972,.015757,.028278,0.0*
1,1,.006,.015757,.028278*
20,1,.006,.015757,.028278,.016,.0255,0.0*
1,1,.006,.016,.0255*
20,1,.006,.016,.0255,.016,-.0255,0.0*
1,1,.006,.016,-.0255*
20,1,.006,.016,-.0255,.015757,-.028278,0.0*
1,1,.006,.015757,-.028278*
20,1,.006,.015757,-.028278,.015035,-.030972,0.0*
1,1,.006,.015035,-.030972*
20,1,.006,.015035,-.030972,.013856,-.0335,0.0*
1,1,.006,.013856,-.0335*
20,1,.006,.013856,-.0335,.012257,-.035785,0.0*
1,1,.006,.012257,-.035785*
20,1,.006,.012257,-.035785,.010285,-.037757,0.0*
1,1,.006,.010285,-.037757*
20,1,.006,.010285,-.037757,.008,-.039356,0.0*
1,1,.006,.008,-.039356*
20,1,.006,.008,-.039356,.005472,-.040535,0.0*
1,1,.006,.005472,-.040535*
20,1,.006,.005472,-.040535,.002778,-.041257,0.0*
1,1,.006,.002778,-.041257*
20,1,.006,.002778,-.041257,0.0,-.0415,0.0*
1,1,.006,0.0,-.0415*
20,1,.006,0.0,-.0415,-.002778,-.041257,0.0*
1,1,.006,-.002778,-.041257*
20,1,.006,-.002778,-.041257,-.005472,-.040535,0.0*
1,1,.006,-.005472,-.040535*
20,1,.006,-.005472,-.040535,-.008,-.039356,0.0*
1,1,.006,-.008,-.039356*
20,1,.006,-.008,-.039356,-.010285,-.037757,0.0*
1,1,.006,-.010285,-.037757*
20,1,.006,-.010285,-.037757,-.012257,-.035785,0.0*
1,1,.006,-.012257,-.035785*
20,1,.006,-.012257,-.035785,-.013856,-.0335,0.0*
1,1,.006,-.013856,-.0335*
20,1,.006,-.013856,-.0335,-.015035,-.030972,0.0*
1,1,.006,-.015035,-.030972*
20,1,.006,-.015035,-.030972,-.015757,-.028278,0.0*
1,1,.006,-.015757,-.028278*
20,1,.006,-.015757,-.028278,-.016,-.0255,0.0*
1,1,.006,-.016,-.0255*
1,1,.006,-.008,-.008*
20,1,.006,-.008,-.008,-.01013,-.00773,0.0*
1,1,.006,-.01013,-.00773*
20,1,.006,-.01013,-.00773,-.012,-.00667,0.0*
1,1,.006,-.012,-.00667*
20,1,.006,-.012,-.00667,-.0136,-.00507,0.0*
1,1,.006,-.0136,-.00507*
20,1,.006,-.0136,-.00507,-.01467,-.0032,0.0*
1,1,.006,-.01467,-.0032*
20,1,.006,-.01467,-.0032,-.0152,-.00107,0.0*
1,1,.006,-.0152,-.00107*
20,1,.006,-.0152,-.00107,-.0152,.00107,0.0*
1,1,.006,-.0152,.00107*
20,1,.006,-.0152,.00107,-.01467,.0032,0.0*
1,1,.006,-.01467,.0032*
20,1,.006,-.01467,.0032,-.0136,.00507,0.0*
1,1,.006,-.0136,.00507*
20,1,.006,-.0136,.00507,-.012,.00667,0.0*
1,1,.006,-.012,.00667*
20,1,.006,-.012,.00667,-.01013,.00773,0.0*
1,1,.006,-.01013,.00773*
20,1,.006,-.01013,.00773,-.008,.008,0.0*
1,1,.006,-.008,.008*
20,1,.006,-.008,.008,-.00587,.00773,0.0*
1,1,.006,-.00587,.00773*
20,1,.006,-.00587,.00773,-.004,.00667,0.0*
1,1,.006,-.004,.00667*
20,1,.006,-.004,.00667,-.0024,.00507,0.0*
1,1,.006,-.0024,.00507*
20,1,.006,-.0024,.00507,-.00133,.0032,0.0*
1,1,.006,-.00133,.0032*
20,1,.006,-.00133,.0032,-.0008,.00107,0.0*
1,1,.006,-.0008,.00107*
20,1,.006,-.0008,.00107,-.0008,-.00107,0.0*
1,1,.006,-.0008,-.00107*
20,1,.006,-.0008,-.00107,-.00133,-.0032,0.0*
1,1,.006,-.00133,-.0032*
20,1,.006,-.00133,-.0032,-.0024,-.00507,0.0*
1,1,.006,-.0024,-.00507*
20,1,.006,-.0024,-.00507,-.004,-.00667,0.0*
1,1,.006,-.004,-.00667*
20,1,.006,-.004,-.00667,-.00587,-.00773,0.0*
1,1,.006,-.00587,-.00773*
20,1,.006,-.00587,-.00773,-.008,-.008,0.0*
1,1,.006,-.008,-.008*
1,1,.006,.01014,.00053*
20,1,.006,.01014,.00053,.01121,.00133,0.0*
1,1,.006,.01121,.00133*
20,1,.006,.01121,.00133,.01201,.00267,0.0*
1,1,.006,.01201,.00267*
20,1,.006,.01201,.00267,.01254,.00453,0.0*
1,1,.006,.01254,.00453*
20,1,.006,.01254,.00453,.01201,.00613,0.0*
1,1,.006,.01201,.00613*
20,1,.006,.01201,.00613,.01094,.0072,0.0*
1,1,.006,.01094,.0072*
20,1,.006,.01094,.0072,.00908,.008,0.0*
1,1,.006,.00908,.008*
20,1,.006,.00908,.008,.00188,.008,0.0*
1,1,.006,.00188,.008*
20,1,.006,.00188,.008,.00188,-.008,0.0*
1,1,.006,.00188,-.008*
20,1,.006,.00188,-.008,.01068,-.008,0.0*
1,1,.006,.01068,-.008*
20,1,.006,.01068,-.008,.01254,-.00693,0.0*
1,1,.006,.01254,-.00693*
20,1,.006,.01254,-.00693,.01361,-.00533,0.0*
1,1,.006,.01361,-.00533*
20,1,.006,.01361,-.00533,.01414,-.00347,0.0*
1,1,.006,.01414,-.00347*
20,1,.006,.01414,-.00347,.01361,-.0016,0.0*
1,1,.006,.01361,-.0016*
20,1,.006,.01361,-.0016,.01201,0.0,0.0*
1,1,.006,.01201,0.0*
20,1,.006,.01201,0.0,.01014,.00053,0.0*
1,1,.006,.01014,.00053*
20,1,.006,.01014,.00053,.00188,.00053,0.0*
1,1,.006,.00188,.00053*
%
%ADD24MACRO24*%
%AMMACRO10*
1,1,.006,.02,.015*
20,1,.006,.02,.015,.02,-.015,0.0*
1,1,.006,.02,-.015*
20,1,.006,.02,-.015,-.02,-.015,0.0*
1,1,.006,-.02,-.015*
20,1,.006,-.02,-.015,-.02,.015,0.0*
1,1,.006,-.02,.015*
20,1,.006,-.02,.015,.02,.015,0.0*
1,1,.006,.02,.015*
1,1,.006,-.0075,-.0075*
20,1,.006,-.0075,-.0075,-.0075,.0075,0.0*
1,1,.006,-.0075,.0075*
20,1,.006,-.0075,.0075,-.0105,.0045,0.0*
1,1,.006,-.0105,.0045*
1,1,.006,-.0105,-.0075*
20,1,.006,-.0105,-.0075,-.0045,-.0075,0.0*
1,1,.006,-.0045,-.0075*
1,1,.006,.00751,.0075*
20,1,.006,.00751,.0075,.00551,.007,0.0*
1,1,.006,.00551,.007*
20,1,.006,.00551,.007,.00401,.00575,0.0*
1,1,.006,.00401,.00575*
20,1,.006,.00401,.00575,.00301,.00425,0.0*
1,1,.006,.00301,.00425*
20,1,.006,.00301,.00425,.00226,.00225,0.0*
1,1,.006,.00226,.00225*
20,1,.006,.00226,.00225,.00201,0.0,0.0*
1,1,.006,.00201,0.0*
20,1,.006,.00201,0.0,.00226,-.00225,0.0*
1,1,.006,.00226,-.00225*
20,1,.006,.00226,-.00225,.00301,-.00425,0.0*
1,1,.006,.00301,-.00425*
20,1,.006,.00301,-.00425,.00401,-.00575,0.0*
1,1,.006,.00401,-.00575*
20,1,.006,.00401,-.00575,.00551,-.007,0.0*
1,1,.006,.00551,-.007*
20,1,.006,.00551,-.007,.00751,-.0075,0.0*
1,1,.006,.00751,-.0075*
20,1,.006,.00751,-.0075,.00951,-.007,0.0*
1,1,.006,.00951,-.007*
20,1,.006,.00951,-.007,.01101,-.00575,0.0*
1,1,.006,.01101,-.00575*
20,1,.006,.01101,-.00575,.01201,-.00425,0.0*
1,1,.006,.01201,-.00425*
20,1,.006,.01201,-.00425,.01276,-.00225,0.0*
1,1,.006,.01276,-.00225*
20,1,.006,.01276,-.00225,.01301,0.0,0.0*
1,1,.006,.01301,0.0*
20,1,.006,.01301,0.0,.01276,.00225,0.0*
1,1,.006,.01276,.00225*
20,1,.006,.01276,.00225,.01201,.00425,0.0*
1,1,.006,.01201,.00425*
20,1,.006,.01201,.00425,.01101,.00575,0.0*
1,1,.006,.01101,.00575*
20,1,.006,.01101,.00575,.00951,.007,0.0*
1,1,.006,.00951,.007*
20,1,.006,.00951,.007,.00751,.0075,0.0*
1,1,.006,.00751,.0075*
%
%ADD10MACRO10*%
%AMMACRO15*
1,1,.006,0.0,.006*
20,1,.006,0.0,.006,-.005196,.003,0.0*
1,1,.006,-.005196,.003*
20,1,.006,-.005196,.003,-.005196,-.003,0.0*
1,1,.006,-.005196,-.003*
20,1,.006,-.005196,-.003,0.0,-.006,0.0*
1,1,.006,0.0,-.006*
20,1,.006,0.0,-.006,.005196,-.003,0.0*
1,1,.006,.005196,-.003*
20,1,.006,.005196,-.003,.005196,.003,0.0*
1,1,.006,.005196,.003*
20,1,.006,.005196,.003,0.0,.006,0.0*
1,1,.006,0.0,.006*
1,1,.006,.0012,-.003*
20,1,.006,.0012,-.003,.0012,.003,0.0*
1,1,.006,.0012,.003*
20,1,.006,.0012,.003,-.0025,-.0013,0.0*
1,1,.006,-.0025,-.0013*
20,1,.006,-.0025,-.0013,.0025,-.0013,0.0*
1,1,.006,.0025,-.0013*
%
%ADD15MACRO15*%
%AMMACRO17*
1,1,.006,-.067,.067*
20,1,.006,-.067,.067,.067,.067,0.0*
1,1,.006,.067,.067*
20,1,.006,.067,.067,.078634,.065982,0.0*
1,1,.006,.078634,.065982*
20,1,.006,.078634,.065982,.089915,.062959,0.0*
1,1,.006,.089915,.062959*
20,1,.006,.089915,.062959,.1005,.058024,0.0*
1,1,.006,.1005,.058024*
20,1,.006,.1005,.058024,.110067,.051325,0.0*
1,1,.006,.110067,.051325*
20,1,.006,.110067,.051325,.118325,.043067,0.0*
1,1,.006,.118325,.043067*
20,1,.006,.118325,.043067,.125024,.0335,0.0*
1,1,.006,.125024,.0335*
20,1,.006,.125024,.0335,.129959,.022915,0.0*
1,1,.006,.129959,.022915*
20,1,.006,.129959,.022915,.132982,.011634,0.0*
1,1,.006,.132982,.011634*
20,1,.006,.132982,.011634,.134,0.0,0.0*
1,1,.006,.134,0.0*
20,1,.006,.134,0.0,.132982,-.011634,0.0*
1,1,.006,.132982,-.011634*
20,1,.006,.132982,-.011634,.129959,-.022915,0.0*
1,1,.006,.129959,-.022915*
20,1,.006,.129959,-.022915,.125024,-.0335,0.0*
1,1,.006,.125024,-.0335*
20,1,.006,.125024,-.0335,.118325,-.043067,0.0*
1,1,.006,.118325,-.043067*
20,1,.006,.118325,-.043067,.110067,-.051325,0.0*
1,1,.006,.110067,-.051325*
20,1,.006,.110067,-.051325,.1005,-.058024,0.0*
1,1,.006,.1005,-.058024*
20,1,.006,.1005,-.058024,.089915,-.062959,0.0*
1,1,.006,.089915,-.062959*
20,1,.006,.089915,-.062959,.078634,-.065982,0.0*
1,1,.006,.078634,-.065982*
20,1,.006,.078634,-.065982,.067,-.067,0.0*
1,1,.006,.067,-.067*
20,1,.006,.067,-.067,-.067,-.067,0.0*
1,1,.006,-.067,-.067*
20,1,.006,-.067,-.067,-.078634,-.065982,0.0*
1,1,.006,-.078634,-.065982*
20,1,.006,-.078634,-.065982,-.089915,-.062959,0.0*
1,1,.006,-.089915,-.062959*
20,1,.006,-.089915,-.062959,-.1005,-.058024,0.0*
1,1,.006,-.1005,-.058024*
20,1,.006,-.1005,-.058024,-.110067,-.051325,0.0*
1,1,.006,-.110067,-.051325*
20,1,.006,-.110067,-.051325,-.118325,-.043067,0.0*
1,1,.006,-.118325,-.043067*
20,1,.006,-.118325,-.043067,-.125024,-.0335,0.0*
1,1,.006,-.125024,-.0335*
20,1,.006,-.125024,-.0335,-.129959,-.022915,0.0*
1,1,.006,-.129959,-.022915*
20,1,.006,-.129959,-.022915,-.132982,-.011634,0.0*
1,1,.006,-.132982,-.011634*
20,1,.006,-.132982,-.011634,-.134,0.0,0.0*
1,1,.006,-.134,0.0*
20,1,.006,-.134,0.0,-.132982,.011634,0.0*
1,1,.006,-.132982,.011634*
20,1,.006,-.132982,.011634,-.129959,.022915,0.0*
1,1,.006,-.129959,.022915*
20,1,.006,-.129959,.022915,-.125024,.0335,0.0*
1,1,.006,-.125024,.0335*
20,1,.006,-.125024,.0335,-.118325,.043067,0.0*
1,1,.006,-.118325,.043067*
20,1,.006,-.118325,.043067,-.110067,.051325,0.0*
1,1,.006,-.110067,.051325*
20,1,.006,-.110067,.051325,-.1005,.058024,0.0*
1,1,.006,-.1005,.058024*
20,1,.006,-.1005,.058024,-.089915,.062959,0.0*
1,1,.006,-.089915,.062959*
20,1,.006,-.089915,.062959,-.078634,.065982,0.0*
1,1,.006,-.078634,.065982*
20,1,.006,-.078634,.065982,-.067,.067,0.0*
1,1,.006,-.067,.067*
1,1,.006,-.0335,-.0335*
20,1,.006,-.0335,-.0335,-.04243,-.03238,0.0*
1,1,.006,-.04243,-.03238*
20,1,.006,-.04243,-.03238,-.05025,-.02792,0.0*
1,1,.006,-.05025,-.02792*
20,1,.006,-.05025,-.02792,-.05695,-.02122,0.0*
1,1,.006,-.05695,-.02122*
20,1,.006,-.05695,-.02122,-.06142,-.0134,0.0*
1,1,.006,-.06142,-.0134*
20,1,.006,-.06142,-.0134,-.06365,-.00447,0.0*
1,1,.006,-.06365,-.00447*
20,1,.006,-.06365,-.00447,-.06365,.00447,0.0*
1,1,.006,-.06365,.00447*
20,1,.006,-.06365,.00447,-.06142,.0134,0.0*
1,1,.006,-.06142,.0134*
20,1,.006,-.06142,.0134,-.05695,.02122,0.0*
1,1,.006,-.05695,.02122*
20,1,.006,-.05695,.02122,-.05025,.02792,0.0*
1,1,.006,-.05025,.02792*
20,1,.006,-.05025,.02792,-.04243,.03238,0.0*
1,1,.006,-.04243,.03238*
20,1,.006,-.04243,.03238,-.0335,.0335,0.0*
1,1,.006,-.0335,.0335*
20,1,.006,-.0335,.0335,-.02457,.03238,0.0*
1,1,.006,-.02457,.03238*
20,1,.006,-.02457,.03238,-.01675,.02792,0.0*
1,1,.006,-.01675,.02792*
20,1,.006,-.01675,.02792,-.01005,.02122,0.0*
1,1,.006,-.01005,.02122*
20,1,.006,-.01005,.02122,-.00558,.0134,0.0*
1,1,.006,-.00558,.0134*
20,1,.006,-.00558,.0134,-.00335,.00447,0.0*
1,1,.006,-.00335,.00447*
20,1,.006,-.00335,.00447,-.00335,-.00447,0.0*
1,1,.006,-.00335,-.00447*
20,1,.006,-.00335,-.00447,-.00558,-.0134,0.0*
1,1,.006,-.00558,-.0134*
20,1,.006,-.00558,-.0134,-.01005,-.02122,0.0*
1,1,.006,-.01005,-.02122*
20,1,.006,-.01005,-.02122,-.01675,-.02792,0.0*
1,1,.006,-.01675,-.02792*
20,1,.006,-.01675,-.02792,-.02457,-.03238,0.0*
1,1,.006,-.02457,-.03238*
20,1,.006,-.02457,-.03238,-.0335,-.0335,0.0*
1,1,.006,-.0335,-.0335*
1,1,.006,.00894,-.0335*
20,1,.006,.00894,-.0335,.00894,.0335,0.0*
1,1,.006,.00894,.0335*
20,1,.006,.00894,.0335,.03128,.0335,0.0*
1,1,.006,.03128,.0335*
20,1,.006,.03128,.0335,.04021,.03015,0.0*
1,1,.006,.04021,.03015*
20,1,.006,.04021,.03015,.04691,.02568,0.0*
1,1,.006,.04691,.02568*
20,1,.006,.04691,.02568,.05249,.01898,0.0*
1,1,.006,.05249,.01898*
20,1,.006,.05249,.01898,.05696,.01117,0.0*
1,1,.006,.05696,.01117*
20,1,.006,.05696,.01117,.05808,0.0,0.0*
1,1,.006,.05808,0.0*
20,1,.006,.05808,0.0,.05696,-.01117,0.0*
1,1,.006,.05696,-.01117*
20,1,.006,.05696,-.01117,.05249,-.01898,0.0*
1,1,.006,.05249,-.01898*
20,1,.006,.05249,-.01898,.04691,-.02569,0.0*
1,1,.006,.04691,-.02569*
20,1,.006,.04691,-.02569,.04021,-.03015,0.0*
1,1,.006,.04021,-.03015*
20,1,.006,.04021,-.03015,.03128,-.0335,0.0*
1,1,.006,.03128,-.0335*
20,1,.006,.03128,-.0335,.00894,-.0335,0.0*
1,1,.006,.00894,-.0335*
%
%ADD17MACRO17*%
%AMMACRO32*
1,1,.006,-.063,-.0315*
20,1,.006,-.063,-.0315,-.063,.0315,0.0*
1,1,.006,-.063,.0315*
20,1,.006,-.063,.0315,-.062043,.04244,0.0*
1,1,.006,-.062043,.04244*
20,1,.006,-.062043,.04244,-.059201,.053047,0.0*
1,1,.006,-.059201,.053047*
20,1,.006,-.059201,.053047,-.05456,.063,0.0*
1,1,.006,-.05456,.063*
20,1,.006,-.05456,.063,-.048261,.071996,0.0*
1,1,.006,-.048261,.071996*
20,1,.006,-.048261,.071996,-.040496,.079761,0.0*
1,1,.006,-.040496,.079761*
20,1,.006,-.040496,.079761,-.0315,.08606,0.0*
1,1,.006,-.0315,.08606*
20,1,.006,-.0315,.08606,-.021547,.090701,0.0*
1,1,.006,-.021547,.090701*
20,1,.006,-.021547,.090701,-.01094,.093543,0.0*
1,1,.006,-.01094,.093543*
20,1,.006,-.01094,.093543,0.0,.0945,0.0*
1,1,.006,0.0,.0945*
20,1,.006,0.0,.0945,.01094,.093543,0.0*
1,1,.006,.01094,.093543*
20,1,.006,.01094,.093543,.021547,.090701,0.0*
1,1,.006,.021547,.090701*
20,1,.006,.021547,.090701,.0315,.08606,0.0*
1,1,.006,.0315,.08606*
20,1,.006,.0315,.08606,.040496,.079761,0.0*
1,1,.006,.040496,.079761*
20,1,.006,.040496,.079761,.048261,.071996,0.0*
1,1,.006,.048261,.071996*
20,1,.006,.048261,.071996,.05456,.063,0.0*
1,1,.006,.05456,.063*
20,1,.006,.05456,.063,.059201,.053047,0.0*
1,1,.006,.059201,.053047*
20,1,.006,.059201,.053047,.062043,.04244,0.0*
1,1,.006,.062043,.04244*
20,1,.006,.062043,.04244,.063,.0315,0.0*
1,1,.006,.063,.0315*
20,1,.006,.063,.0315,.063,-.0315,0.0*
1,1,.006,.063,-.0315*
20,1,.006,.063,-.0315,.062043,-.04244,0.0*
1,1,.006,.062043,-.04244*
20,1,.006,.062043,-.04244,.059201,-.053047,0.0*
1,1,.006,.059201,-.053047*
20,1,.006,.059201,-.053047,.05456,-.063,0.0*
1,1,.006,.05456,-.063*
20,1,.006,.05456,-.063,.048261,-.071996,0.0*
1,1,.006,.048261,-.071996*
20,1,.006,.048261,-.071996,.040496,-.079761,0.0*
1,1,.006,.040496,-.079761*
20,1,.006,.040496,-.079761,.0315,-.08606,0.0*
1,1,.006,.0315,-.08606*
20,1,.006,.0315,-.08606,.021547,-.090701,0.0*
1,1,.006,.021547,-.090701*
20,1,.006,.021547,-.090701,.01094,-.093543,0.0*
1,1,.006,.01094,-.093543*
20,1,.006,.01094,-.093543,0.0,-.0945,0.0*
1,1,.006,0.0,-.0945*
20,1,.006,0.0,-.0945,-.01094,-.093543,0.0*
1,1,.006,-.01094,-.093543*
20,1,.006,-.01094,-.093543,-.021547,-.090701,0.0*
1,1,.006,-.021547,-.090701*
20,1,.006,-.021547,-.090701,-.0315,-.08606,0.0*
1,1,.006,-.0315,-.08606*
20,1,.006,-.0315,-.08606,-.040496,-.079761,0.0*
1,1,.006,-.040496,-.079761*
20,1,.006,-.040496,-.079761,-.048261,-.071996,0.0*
1,1,.006,-.048261,-.071996*
20,1,.006,-.048261,-.071996,-.05456,-.063,0.0*
1,1,.006,-.05456,-.063*
20,1,.006,-.05456,-.063,-.059201,-.053047,0.0*
1,1,.006,-.059201,-.053047*
20,1,.006,-.059201,-.053047,-.062043,-.04244,0.0*
1,1,.006,-.062043,-.04244*
20,1,.006,-.062043,-.04244,-.063,-.0315,0.0*
1,1,.006,-.063,-.0315*
1,1,.006,-.0315,-.0315*
20,1,.006,-.0315,-.0315,-.0399,-.03045,0.0*
1,1,.006,-.0399,-.03045*
20,1,.006,-.0399,-.03045,-.04725,-.02625,0.0*
1,1,.006,-.04725,-.02625*
20,1,.006,-.04725,-.02625,-.05355,-.01995,0.0*
1,1,.006,-.05355,-.01995*
20,1,.006,-.05355,-.01995,-.05775,-.0126,0.0*
1,1,.006,-.05775,-.0126*
20,1,.006,-.05775,-.0126,-.05985,-.0042,0.0*
1,1,.006,-.05985,-.0042*
20,1,.006,-.05985,-.0042,-.05985,.0042,0.0*
1,1,.006,-.05985,.0042*
20,1,.006,-.05985,.0042,-.05775,.0126,0.0*
1,1,.006,-.05775,.0126*
20,1,.006,-.05775,.0126,-.05355,.01995,0.0*
1,1,.006,-.05355,.01995*
20,1,.006,-.05355,.01995,-.04725,.02625,0.0*
1,1,.006,-.04725,.02625*
20,1,.006,-.04725,.02625,-.0399,.03045,0.0*
1,1,.006,-.0399,.03045*
20,1,.006,-.0399,.03045,-.0315,.0315,0.0*
1,1,.006,-.0315,.0315*
20,1,.006,-.0315,.0315,-.0231,.03045,0.0*
1,1,.006,-.0231,.03045*
20,1,.006,-.0231,.03045,-.01575,.02625,0.0*
1,1,.006,-.01575,.02625*
20,1,.006,-.01575,.02625,-.00945,.01995,0.0*
1,1,.006,-.00945,.01995*
20,1,.006,-.00945,.01995,-.00525,.0126,0.0*
1,1,.006,-.00525,.0126*
20,1,.006,-.00525,.0126,-.00315,.0042,0.0*
1,1,.006,-.00315,.0042*
20,1,.006,-.00315,.0042,-.00315,-.0042,0.0*
1,1,.006,-.00315,-.0042*
20,1,.006,-.00315,-.0042,-.00525,-.0126,0.0*
1,1,.006,-.00525,-.0126*
20,1,.006,-.00525,-.0126,-.00945,-.01995,0.0*
1,1,.006,-.00945,-.01995*
20,1,.006,-.00945,-.01995,-.01575,-.02625,0.0*
1,1,.006,-.01575,-.02625*
20,1,.006,-.01575,-.02625,-.0231,-.03045,0.0*
1,1,.006,-.0231,-.03045*
20,1,.006,-.0231,-.03045,-.0315,-.0315,0.0*
1,1,.006,-.0315,-.0315*
1,1,.006,.05461,.02625*
20,1,.006,.05461,.02625,.04831,.0294,0.0*
1,1,.006,.04831,.0294*
20,1,.006,.04831,.0294,.04096,.0315,0.0*
1,1,.006,.04096,.0315*
20,1,.006,.04096,.0315,.03256,.0315,0.0*
1,1,.006,.03256,.0315*
20,1,.006,.03256,.0315,.02311,.02835,0.0*
1,1,.006,.02311,.02835*
20,1,.006,.02311,.02835,.01576,.0231,0.0*
1,1,.006,.01576,.0231*
20,1,.006,.01576,.0231,.01051,.0168,0.0*
1,1,.006,.01051,.0168*
20,1,.006,.01051,.0168,.00631,.0063,0.0*
1,1,.006,.00631,.0063*
20,1,.006,.00631,.0063,.00526,-.00315,0.0*
1,1,.006,.00526,-.00315*
20,1,.006,.00526,-.00315,.00736,-.0126,0.0*
1,1,.006,.00736,-.0126*
20,1,.006,.00736,-.0126,.01051,-.0189,0.0*
1,1,.006,.01051,-.0189*
20,1,.006,.01051,-.0189,.01681,-.0252,0.0*
1,1,.006,.01681,-.0252*
20,1,.006,.01681,-.0252,.02416,-.0294,0.0*
1,1,.006,.02416,-.0294*
20,1,.006,.02416,-.0294,.03151,-.0315,0.0*
1,1,.006,.03151,-.0315*
20,1,.006,.03151,-.0315,.03886,-.0315,0.0*
1,1,.006,.03886,-.0315*
20,1,.006,.03886,-.0315,.04621,-.0294,0.0*
1,1,.006,.04621,-.0294*
20,1,.006,.04621,-.0294,.05251,-.02625,0.0*
1,1,.006,.05251,-.02625*
20,1,.006,.05251,-.02625,.05776,-.02205,0.0*
1,1,.006,.05776,-.02205*
%
%ADD32MACRO32*%
%AMMACRO23*
1,1,.006,-.0035,.0105*
20,1,.006,-.0035,.0105,.0035,.0105,0.0*
1,1,.006,.0035,.0105*
20,1,.006,.0035,.0105,.005323,.01034,0.0*
1,1,.006,.005323,.01034*
20,1,.006,.005323,.01034,.007091,.009867,0.0*
1,1,.006,.007091,.009867*
20,1,.006,.007091,.009867,.00875,.009093,0.0*
1,1,.006,.00875,.009093*
20,1,.006,.00875,.009093,.010249,.008043,0.0*
1,1,.006,.010249,.008043*
20,1,.006,.010249,.008043,.011543,.006749,0.0*
1,1,.006,.011543,.006749*
20,1,.006,.011543,.006749,.012593,.00525,0.0*
1,1,.006,.012593,.00525*
20,1,.006,.012593,.00525,.013367,.003591,0.0*
1,1,.006,.013367,.003591*
20,1,.006,.013367,.003591,.01384,.001823,0.0*
1,1,.006,.01384,.001823*
20,1,.006,.01384,.001823,.014,0.0,0.0*
1,1,.006,.014,0.0*
20,1,.006,.014,0.0,.01384,-.001823,0.0*
1,1,.006,.01384,-.001823*
20,1,.006,.01384,-.001823,.013367,-.003591,0.0*
1,1,.006,.013367,-.003591*
20,1,.006,.013367,-.003591,.012593,-.00525,0.0*
1,1,.006,.012593,-.00525*
20,1,.006,.012593,-.00525,.011543,-.006749,0.0*
1,1,.006,.011543,-.006749*
20,1,.006,.011543,-.006749,.010249,-.008043,0.0*
1,1,.006,.010249,-.008043*
20,1,.006,.010249,-.008043,.00875,-.009093,0.0*
1,1,.006,.00875,-.009093*
20,1,.006,.00875,-.009093,.007091,-.009867,0.0*
1,1,.006,.007091,-.009867*
20,1,.006,.007091,-.009867,.005323,-.01034,0.0*
1,1,.006,.005323,-.01034*
20,1,.006,.005323,-.01034,.0035,-.0105,0.0*
1,1,.006,.0035,-.0105*
20,1,.006,.0035,-.0105,-.0035,-.0105,0.0*
1,1,.006,-.0035,-.0105*
20,1,.006,-.0035,-.0105,-.005323,-.01034,0.0*
1,1,.006,-.005323,-.01034*
20,1,.006,-.005323,-.01034,-.007091,-.009867,0.0*
1,1,.006,-.007091,-.009867*
20,1,.006,-.007091,-.009867,-.00875,-.009093,0.0*
1,1,.006,-.00875,-.009093*
20,1,.006,-.00875,-.009093,-.010249,-.008043,0.0*
1,1,.006,-.010249,-.008043*
20,1,.006,-.010249,-.008043,-.011543,-.006749,0.0*
1,1,.006,-.011543,-.006749*
20,1,.006,-.011543,-.006749,-.012593,-.00525,0.0*
1,1,.006,-.012593,-.00525*
20,1,.006,-.012593,-.00525,-.013367,-.003591,0.0*
1,1,.006,-.013367,-.003591*
20,1,.006,-.013367,-.003591,-.01384,-.001823,0.0*
1,1,.006,-.01384,-.001823*
20,1,.006,-.01384,-.001823,-.014,0.0,0.0*
1,1,.006,-.014,0.0*
20,1,.006,-.014,0.0,-.01384,.001823,0.0*
1,1,.006,-.01384,.001823*
20,1,.006,-.01384,.001823,-.013367,.003591,0.0*
1,1,.006,-.013367,.003591*
20,1,.006,-.013367,.003591,-.012593,.00525,0.0*
1,1,.006,-.012593,.00525*
20,1,.006,-.012593,.00525,-.011543,.006749,0.0*
1,1,.006,-.011543,.006749*
20,1,.006,-.011543,.006749,-.010249,.008043,0.0*
1,1,.006,-.010249,.008043*
20,1,.006,-.010249,.008043,-.00875,.009093,0.0*
1,1,.006,-.00875,.009093*
20,1,.006,-.00875,.009093,-.007091,.009867,0.0*
1,1,.006,-.007091,.009867*
20,1,.006,-.007091,.009867,-.005323,.01034,0.0*
1,1,.006,-.005323,.01034*
20,1,.006,-.005323,.01034,-.0035,.0105,0.0*
1,1,.006,-.0035,.0105*
1,1,.006,0.0,-.00525*
20,1,.006,0.0,-.00525,.00122,-.00508,0.0*
1,1,.006,.00122,-.00508*
20,1,.006,.00122,-.00508,.00262,-.00455,0.0*
1,1,.006,.00262,-.00455*
20,1,.006,.00262,-.00455,.0035,-.00368,0.0*
1,1,.006,.0035,-.00368*
20,1,.006,.0035,-.00368,.00385,-.00245,0.0*
1,1,.006,.00385,-.00245*
20,1,.006,.00385,-.00245,.0035,-.00123,0.0*
1,1,.006,.0035,-.00123*
20,1,.006,.0035,-.00123,.00245,-.00018,0.0*
1,1,.006,.00245,-.00018*
20,1,.006,.00245,-.00018,.00087,.00035,0.0*
1,1,.006,.00087,.00035*
20,1,.006,.00087,.00035,-.00087,.00035,0.0*
1,1,.006,-.00087,.00035*
20,1,.006,-.00087,.00035,-.00193,.0007,0.0*
1,1,.006,-.00193,.0007*
20,1,.006,-.00193,.0007,-.0028,.00157,0.0*
1,1,.006,-.0028,.00157*
20,1,.006,-.0028,.00157,-.00315,.0028,0.0*
1,1,.006,-.00315,.0028*
20,1,.006,-.00315,.0028,-.00262,.00402,0.0*
1,1,.006,-.00262,.00402*
20,1,.006,-.00262,.00402,-.0014,.0049,0.0*
1,1,.006,-.0014,.0049*
20,1,.006,-.0014,.0049,0.0,.00525,0.0*
1,1,.006,0.0,.00525*
20,1,.006,0.0,.00525,.0014,.0049,0.0*
1,1,.006,.0014,.0049*
20,1,.006,.0014,.0049,.00262,.00402,0.0*
1,1,.006,.00262,.00402*
20,1,.006,.00262,.00402,.00315,.0028,0.0*
1,1,.006,.00315,.0028*
20,1,.006,.00315,.0028,.0028,.00157,0.0*
1,1,.006,.0028,.00157*
20,1,.006,.0028,.00157,.00193,.0007,0.0*
1,1,.006,.00193,.0007*
20,1,.006,.00193,.0007,.00087,.00035,0.0*
1,1,.006,.00087,.00035*
20,1,.006,.00087,.00035,-.00087,.00035,0.0*
1,1,.006,-.00087,.00035*
20,1,.006,-.00087,.00035,-.00245,-.00018,0.0*
1,1,.006,-.00245,-.00018*
20,1,.006,-.00245,-.00018,-.0035,-.00123,0.0*
1,1,.006,-.0035,-.00123*
20,1,.006,-.0035,-.00123,-.00385,-.00245,0.0*
1,1,.006,-.00385,-.00245*
20,1,.006,-.00385,-.00245,-.0035,-.00368,0.0*
1,1,.006,-.0035,-.00368*
20,1,.006,-.0035,-.00368,-.00262,-.00455,0.0*
1,1,.006,-.00262,-.00455*
20,1,.006,-.00262,-.00455,-.00122,-.00508,0.0*
1,1,.006,-.00122,-.00508*
20,1,.006,-.00122,-.00508,0.0,-.00525,0.0*
1,1,.006,0.0,-.00525*
%
%ADD23MACRO23*%
%AMMACRO14*
1,1,.006,.069,0.0*
20,1,.006,.069,0.0,.067952,-.011982,0.0*
1,1,.006,.067952,-.011982*
20,1,.006,.067952,-.011982,.064839,-.023599,0.0*
1,1,.006,.064839,-.023599*
20,1,.006,.064839,-.023599,.059756,-.0345,0.0*
1,1,.006,.059756,-.0345*
20,1,.006,.059756,-.0345,.052857,-.044352,0.0*
1,1,.006,.052857,-.044352*
20,1,.006,.052857,-.044352,.044352,-.052857,0.0*
1,1,.006,.044352,-.052857*
20,1,.006,.044352,-.052857,.0345,-.059756,0.0*
1,1,.006,.0345,-.059756*
20,1,.006,.0345,-.059756,.023599,-.064839,0.0*
1,1,.006,.023599,-.064839*
20,1,.006,.023599,-.064839,.011982,-.067952,0.0*
1,1,.006,.011982,-.067952*
20,1,.006,.011982,-.067952,0.0,-.069,0.0*
1,1,.006,0.0,-.069*
20,1,.006,0.0,-.069,-.011982,-.067952,0.0*
1,1,.006,-.011982,-.067952*
20,1,.006,-.011982,-.067952,-.023599,-.064839,0.0*
1,1,.006,-.023599,-.064839*
20,1,.006,-.023599,-.064839,-.0345,-.059756,0.0*
1,1,.006,-.0345,-.059756*
20,1,.006,-.0345,-.059756,-.044352,-.052857,0.0*
1,1,.006,-.044352,-.052857*
20,1,.006,-.044352,-.052857,-.052857,-.044352,0.0*
1,1,.006,-.052857,-.044352*
20,1,.006,-.052857,-.044352,-.059756,-.0345,0.0*
1,1,.006,-.059756,-.0345*
20,1,.006,-.059756,-.0345,-.064839,-.023599,0.0*
1,1,.006,-.064839,-.023599*
20,1,.006,-.064839,-.023599,-.067952,-.011982,0.0*
1,1,.006,-.067952,-.011982*
20,1,.006,-.067952,-.011982,-.069,0.0,0.0*
1,1,.006,-.069,0.0*
20,1,.006,-.069,0.0,-.067952,.011982,0.0*
1,1,.006,-.067952,.011982*
20,1,.006,-.067952,.011982,-.064839,.023599,0.0*
1,1,.006,-.064839,.023599*
20,1,.006,-.064839,.023599,-.059756,.0345,0.0*
1,1,.006,-.059756,.0345*
20,1,.006,-.059756,.0345,-.052857,.044352,0.0*
1,1,.006,-.052857,.044352*
20,1,.006,-.052857,.044352,-.044352,.052857,0.0*
1,1,.006,-.044352,.052857*
20,1,.006,-.044352,.052857,-.0345,.059756,0.0*
1,1,.006,-.0345,.059756*
20,1,.006,-.0345,.059756,-.023599,.064839,0.0*
1,1,.006,-.023599,.064839*
20,1,.006,-.023599,.064839,-.011982,.067952,0.0*
1,1,.006,-.011982,.067952*
20,1,.006,-.011982,.067952,0.0,.069,0.0*
1,1,.006,0.0,.069*
20,1,.006,0.0,.069,.011982,.067952,0.0*
1,1,.006,.011982,.067952*
20,1,.006,.011982,.067952,.023599,.064839,0.0*
1,1,.006,.023599,.064839*
20,1,.006,.023599,.064839,.0345,.059756,0.0*
1,1,.006,.0345,.059756*
20,1,.006,.0345,.059756,.044352,.052857,0.0*
1,1,.006,.044352,.052857*
20,1,.006,.044352,.052857,.052857,.044352,0.0*
1,1,.006,.052857,.044352*
20,1,.006,.052857,.044352,.059756,.0345,0.0*
1,1,.006,.059756,.0345*
20,1,.006,.059756,.0345,.064839,.023599,0.0*
1,1,.006,.064839,.023599*
20,1,.006,.064839,.023599,.067952,.011982,0.0*
1,1,.006,.067952,.011982*
20,1,.006,.067952,.011982,.069,0.0,0.0*
1,1,.006,.069,0.0*
1,1,.006,-.0345,-.0345*
20,1,.006,-.0345,-.0345,-.0345,.0345,0.0*
1,1,.006,-.0345,.0345*
20,1,.006,-.0345,.0345,-.0483,.0207,0.0*
1,1,.006,-.0483,.0207*
1,1,.006,-.0483,-.0345*
20,1,.006,-.0483,-.0345,-.0207,-.0345,0.0*
1,1,.006,-.0207,-.0345*
1,1,.006,.03451,-.0345*
20,1,.006,.03451,-.0345,.03451,.0345,0.0*
1,1,.006,.03451,.0345*
20,1,.006,.03451,.0345,.02071,.0207,0.0*
1,1,.006,.02071,.0207*
1,1,.006,.02071,-.0345*
20,1,.006,.02071,-.0345,.04831,-.0345,0.0*
1,1,.006,.04831,-.0345*
%
%ADD14MACRO14*%
%AMMACRO11*
1,1,.006,0.0,.008*
20,1,.006,0.0,.008,.008,-.008,0.0*
1,1,.006,.008,-.008*
20,1,.006,.008,-.008,-.008,-.008,0.0*
1,1,.006,-.008,-.008*
20,1,.006,-.008,-.008,0.0,.008,0.0*
1,1,.006,0.0,.008*
1,1,.006,-.00027,-.004*
20,1,.006,-.00027,-.004,0.0,-.00227,0.0*
1,1,.006,0.0,-.00227*
20,1,.006,0.0,-.00227,.0004,-.0008,0.0*
1,1,.006,.0004,-.0008*
20,1,.006,.0004,-.0008,.00093,.00053,0.0*
1,1,.006,.00093,.00053*
20,1,.006,.00093,.00053,.0016,.002,0.0*
1,1,.006,.0016,.002*
20,1,.006,.0016,.002,.00267,.004,0.0*
1,1,.006,.00267,.004*
20,1,.006,.00267,.004,-.00267,.004,0.0*
1,1,.006,-.00267,.004*
%
%ADD11MACRO11*%
%AMMACRO35*
1,1,.006,-.013125,.004375*
20,1,.006,-.013125,.004375,-.012926,.006654,0.0*
1,1,.006,-.012926,.006654*
20,1,.006,-.012926,.006654,-.012333,.008864,0.0*
1,1,.006,-.012333,.008864*
20,1,.006,-.012333,.008864,-.011367,.010937,0.0*
1,1,.006,-.011367,.010937*
20,1,.006,-.011367,.010937,-.010054,.012812,0.0*
1,1,.006,-.010054,.012812*
20,1,.006,-.010054,.012812,-.008437,.014429,0.0*
1,1,.006,-.008437,.014429*
20,1,.006,-.008437,.014429,-.006563,.015742,0.0*
1,1,.006,-.006563,.015742*
20,1,.006,-.006563,.015742,-.004489,.016708,0.0*
1,1,.006,-.004489,.016708*
20,1,.006,-.004489,.016708,-.002279,.017301,0.0*
1,1,.006,-.002279,.017301*
20,1,.006,-.002279,.017301,0.0,.0175,0.0*
1,1,.006,0.0,.0175*
20,1,.006,0.0,.0175,.002279,.017301,0.0*
1,1,.006,.002279,.017301*
20,1,.006,.002279,.017301,.004489,.016708,0.0*
1,1,.006,.004489,.016708*
20,1,.006,.004489,.016708,.006562,.015742,0.0*
1,1,.006,.006562,.015742*
20,1,.006,.006562,.015742,.008437,.014429,0.0*
1,1,.006,.008437,.014429*
20,1,.006,.008437,.014429,.010054,.012812,0.0*
1,1,.006,.010054,.012812*
20,1,.006,.010054,.012812,.011367,.010938,0.0*
1,1,.006,.011367,.010938*
20,1,.006,.011367,.010938,.012333,.008864,0.0*
1,1,.006,.012333,.008864*
20,1,.006,.012333,.008864,.012926,.006654,0.0*
1,1,.006,.012926,.006654*
20,1,.006,.012926,.006654,.013125,.004375,0.0*
1,1,.006,.013125,.004375*
20,1,.006,.013125,.004375,.013125,-.004375,0.0*
1,1,.006,.013125,-.004375*
20,1,.006,.013125,-.004375,.012926,-.006654,0.0*
1,1,.006,.012926,-.006654*
20,1,.006,.012926,-.006654,.012333,-.008864,0.0*
1,1,.006,.012333,-.008864*
20,1,.006,.012333,-.008864,.011367,-.010937,0.0*
1,1,.006,.011367,-.010937*
20,1,.006,.011367,-.010937,.010054,-.012812,0.0*
1,1,.006,.010054,-.012812*
20,1,.006,.010054,-.012812,.008437,-.014429,0.0*
1,1,.006,.008437,-.014429*
20,1,.006,.008437,-.014429,.006563,-.015742,0.0*
1,1,.006,.006563,-.015742*
20,1,.006,.006563,-.015742,.004489,-.016708,0.0*
1,1,.006,.004489,-.016708*
20,1,.006,.004489,-.016708,.002279,-.017301,0.0*
1,1,.006,.002279,-.017301*
20,1,.006,.002279,-.017301,0.0,-.0175,0.0*
1,1,.006,0.0,-.0175*
20,1,.006,0.0,-.0175,-.002279,-.017301,0.0*
1,1,.006,-.002279,-.017301*
20,1,.006,-.002279,-.017301,-.004489,-.016708,0.0*
1,1,.006,-.004489,-.016708*
20,1,.006,-.004489,-.016708,-.006562,-.015742,0.0*
1,1,.006,-.006562,-.015742*
20,1,.006,-.006562,-.015742,-.008437,-.014429,0.0*
1,1,.006,-.008437,-.014429*
20,1,.006,-.008437,-.014429,-.010054,-.012812,0.0*
1,1,.006,-.010054,-.012812*
20,1,.006,-.010054,-.012812,-.011367,-.010938,0.0*
1,1,.006,-.011367,-.010938*
20,1,.006,-.011367,-.010938,-.012333,-.008864,0.0*
1,1,.006,-.012333,-.008864*
20,1,.006,-.012333,-.008864,-.012926,-.006654,0.0*
1,1,.006,-.012926,-.006654*
20,1,.006,-.012926,-.006654,-.013125,-.004375,0.0*
1,1,.006,-.013125,-.004375*
20,1,.006,-.013125,-.004375,-.013125,.004375,0.0*
1,1,.006,-.013125,.004375*
1,1,.006,-.00372,-.00503*
20,1,.006,-.00372,-.00503,-.00219,-.00612,0.0*
1,1,.006,-.00219,-.00612*
20,1,.006,-.00219,-.00612,-.00044,-.00656,0.0*
1,1,.006,-.00044,-.00656*
20,1,.006,-.00044,-.00656,.00131,-.00612,0.0*
1,1,.006,.00131,-.00612*
20,1,.006,.00131,-.00612,.00284,-.00481,0.0*
1,1,.006,.00284,-.00481*
20,1,.006,.00284,-.00481,.00394,-.00284,0.0*
1,1,.006,.00394,-.00284*
20,1,.006,.00394,-.00284,.00437,-.00087,0.0*
1,1,.006,.00437,-.00087*
20,1,.006,.00437,-.00087,.00437,.00153,0.0*
1,1,.006,.00437,.00153*
20,1,.006,.00437,.00153,.00394,.0035,0.0*
1,1,.006,.00394,.0035*
20,1,.006,.00394,.0035,.00284,.00525,0.0*
1,1,.006,.00284,.00525*
20,1,.006,.00284,.00525,.00153,.00612,0.0*
1,1,.006,.00153,.00612*
20,1,.006,.00153,.00612,0.0,.00656,0.0*
1,1,.006,0.0,.00656*
20,1,.006,0.0,.00656,-.00175,.00612,0.0*
1,1,.006,-.00175,.00612*
20,1,.006,-.00175,.00612,-.00306,.00525,0.0*
1,1,.006,-.00306,.00525*
20,1,.006,-.00306,.00525,-.00394,.00394,0.0*
1,1,.006,-.00394,.00394*
20,1,.006,-.00394,.00394,-.00437,.00219,0.0*
1,1,.006,-.00437,.00219*
20,1,.006,-.00437,.00219,-.00394,.00066,0.0*
1,1,.006,-.00394,.00066*
20,1,.006,-.00394,.00066,-.00284,-.00087,0.0*
1,1,.006,-.00284,-.00087*
20,1,.006,-.00284,-.00087,-.00153,-.00175,0.0*
1,1,.006,-.00153,-.00175*
20,1,.006,-.00153,-.00175,0.0,-.00197,0.0*
1,1,.006,0.0,-.00197*
20,1,.006,0.0,-.00197,.00175,-.00153,0.0*
1,1,.006,.00175,-.00153*
20,1,.006,.00175,-.00153,.00306,-.00044,0.0*
1,1,.006,.00306,-.00044*
20,1,.006,.00306,-.00044,.00437,.00153,0.0*
1,1,.006,.00437,.00153*
%
%ADD35MACRO35*%
%ADD36C,.02*%
%ADD37C,.006*%
G75*
%LPD*%
G75*
G54D10*
X61024Y34449D03*
X33464D03*
X56102Y24606D03*
X38386D03*
X108268Y44292D03*
X80708D03*
X103346Y34449D03*
X85630D03*
X1105450Y612075D03*
G54D11*
X66435Y8514D03*
X61435D03*
X56435D03*
X51435D03*
X46435D03*
X41435D03*
X36435D03*
X31435D03*
X26435D03*
X21435D03*
X16435D03*
X8514Y10593D03*
Y15593D03*
Y20593D03*
Y25593D03*
Y30593D03*
Y35593D03*
Y40593D03*
Y45593D03*
Y50593D03*
Y55593D03*
Y60593D03*
Y65593D03*
Y70593D03*
Y75593D03*
Y80593D03*
Y85593D03*
Y90593D03*
Y95593D03*
Y100593D03*
Y105593D03*
Y110593D03*
Y115593D03*
Y120593D03*
Y125593D03*
Y130593D03*
Y135593D03*
Y140593D03*
Y145593D03*
Y150593D03*
Y155593D03*
Y160593D03*
Y165593D03*
Y170593D03*
Y175593D03*
Y180593D03*
Y185593D03*
Y190593D03*
Y195593D03*
Y200593D03*
Y205593D03*
Y210593D03*
Y215593D03*
Y220593D03*
Y225593D03*
Y230593D03*
Y235593D03*
Y240593D03*
Y245593D03*
Y250593D03*
Y255593D03*
Y260593D03*
Y265593D03*
Y270593D03*
Y275593D03*
Y280593D03*
Y285593D03*
Y290593D03*
Y295593D03*
Y300593D03*
Y305593D03*
Y310593D03*
Y315593D03*
Y320593D03*
Y325593D03*
Y330593D03*
Y335593D03*
Y340593D03*
Y345593D03*
Y350593D03*
Y355593D03*
Y360593D03*
Y365593D03*
Y370593D03*
Y375593D03*
Y380593D03*
Y385593D03*
Y390593D03*
Y395593D03*
Y400593D03*
Y405593D03*
Y410593D03*
Y415593D03*
Y420593D03*
Y425593D03*
Y430593D03*
Y435593D03*
Y440593D03*
Y445593D03*
Y450593D03*
Y455593D03*
Y460593D03*
Y465593D03*
Y470593D03*
Y475593D03*
Y480593D03*
Y485593D03*
Y490593D03*
Y495593D03*
Y500593D03*
Y505593D03*
Y510593D03*
Y515593D03*
Y520593D03*
Y525593D03*
Y530593D03*
Y535593D03*
Y540593D03*
Y545593D03*
Y550593D03*
Y555593D03*
Y560593D03*
Y565593D03*
Y570593D03*
Y575593D03*
Y580593D03*
Y585593D03*
Y590593D03*
Y595593D03*
Y600593D03*
Y605593D03*
Y610593D03*
Y615593D03*
Y620593D03*
Y625593D03*
Y630593D03*
Y635593D03*
Y640593D03*
Y645593D03*
Y650593D03*
Y655593D03*
Y660593D03*
Y665593D03*
Y670593D03*
Y675593D03*
Y680593D03*
Y685593D03*
Y690593D03*
Y695593D03*
Y700593D03*
Y705593D03*
Y710593D03*
Y715593D03*
Y720593D03*
X9942Y725256D03*
X12178Y729728D03*
X14414Y734200D03*
X16650Y738672D03*
X18886Y743144D03*
X21122Y747617D03*
X23358Y752089D03*
X111683Y63266D03*
Y58266D03*
Y23266D03*
Y18266D03*
Y13266D03*
X111435Y8514D03*
X106435D03*
X101435D03*
X96435D03*
X91435D03*
X86435D03*
X81435D03*
X76435D03*
X71435D03*
X111683Y118266D03*
Y113266D03*
Y108266D03*
Y103266D03*
Y98266D03*
Y93266D03*
Y88266D03*
Y83266D03*
Y78266D03*
Y73266D03*
Y68266D03*
Y203266D03*
Y198266D03*
Y193266D03*
Y188266D03*
Y183266D03*
Y178266D03*
Y173266D03*
Y168266D03*
Y163266D03*
Y158266D03*
Y153266D03*
Y148266D03*
Y278266D03*
Y273266D03*
Y268266D03*
Y263266D03*
Y258266D03*
Y253266D03*
Y248266D03*
Y243266D03*
Y238266D03*
Y233266D03*
Y228266D03*
Y223266D03*
Y218266D03*
Y213266D03*
Y208266D03*
Y348266D03*
Y343266D03*
Y338266D03*
Y333266D03*
Y328266D03*
Y323266D03*
Y318266D03*
Y313266D03*
Y308266D03*
Y303266D03*
Y298266D03*
Y293266D03*
Y288266D03*
Y283266D03*
Y418266D03*
Y413266D03*
Y408266D03*
Y403266D03*
Y398266D03*
Y393266D03*
Y388266D03*
Y383266D03*
Y378266D03*
Y373266D03*
Y368266D03*
Y363266D03*
Y358266D03*
Y353266D03*
X103940Y635460D03*
X76118Y625275D03*
X81118D03*
X86300Y703200D03*
X99337Y683756D03*
Y678756D03*
Y673756D03*
X86300Y708000D03*
X95200Y667500D03*
X90400D03*
X85600D03*
X76549Y680547D03*
Y675547D03*
X81549Y680547D03*
Y675547D03*
X134223Y691027D03*
X122335Y660582D03*
Y655782D03*
X76395Y755266D03*
X81395D03*
X86395D03*
X91395D03*
X96395D03*
X101395D03*
X106395D03*
X111395D03*
X116395D03*
X121395D03*
X126395D03*
X131395D03*
X136395D03*
X141395D03*
X108928Y744775D03*
X113928D03*
X118928D03*
X123928D03*
X103928D03*
X98928D03*
X93928D03*
X83125Y719240D03*
Y724040D03*
X196700Y704985D03*
X201700D03*
X206700D03*
X211700D03*
X191700D03*
X146395Y755266D03*
X151395D03*
X156395D03*
X161395D03*
X166395D03*
X171395D03*
X176395D03*
X181395D03*
X186395D03*
X191395D03*
X196395D03*
X201395D03*
X206395D03*
X211395D03*
X155400Y717700D03*
X221700Y704985D03*
X226700D03*
X216700D03*
X216395Y755266D03*
X221395D03*
X226395D03*
X231395D03*
X236395D03*
X241395D03*
X246395D03*
X251395D03*
X256395D03*
X261395D03*
X266395D03*
X271395D03*
X276395D03*
X281395D03*
X249200Y733700D03*
Y728700D03*
Y723700D03*
Y718700D03*
Y738500D03*
X330546Y8514D03*
X325546D03*
X320546D03*
X315546D03*
X310546D03*
X305546D03*
X300546D03*
X296034Y9002D03*
Y14002D03*
Y19002D03*
Y24002D03*
Y29002D03*
Y34002D03*
Y39002D03*
Y44002D03*
Y49002D03*
Y54002D03*
Y59002D03*
Y64002D03*
Y69002D03*
Y74002D03*
Y79002D03*
Y84002D03*
Y89002D03*
Y94002D03*
Y99002D03*
Y104002D03*
Y109002D03*
Y114002D03*
Y119002D03*
Y124002D03*
Y129002D03*
Y134002D03*
Y139002D03*
X334782Y184928D03*
X321182Y202574D03*
Y197774D03*
X305882Y195474D03*
X305382Y190174D03*
X334882Y195478D03*
Y200478D03*
Y190478D03*
X335061Y222578D03*
X335100Y218378D03*
X323492Y214234D03*
X305862Y210014D03*
X335000Y621200D03*
Y615400D03*
Y610200D03*
X325600Y640100D03*
X330400D03*
X335200D03*
X322000Y653081D03*
X312400D03*
X317200D03*
X307600D03*
X298700Y674600D03*
X303700D03*
X286395Y755266D03*
X291395D03*
X296395D03*
X301395D03*
X306395D03*
X311395D03*
X316395D03*
X321395D03*
X326395D03*
X331395D03*
X336395D03*
X315520Y711720D03*
X320320D03*
X325120D03*
X305559Y720973D03*
X310559D03*
X305559Y725973D03*
X310559D03*
X299500Y725400D03*
X373073Y201889D03*
X399754Y706071D03*
X389168Y743572D03*
X391404Y739100D03*
X393640Y734628D03*
X395876Y730156D03*
X398112Y725684D03*
X399754Y716071D03*
Y711071D03*
X435000Y29000D03*
X438500Y25500D03*
Y32500D03*
X491500Y71600D03*
X496500D03*
X491500Y76600D03*
X496500D03*
X556510Y53626D03*
X516693Y46345D03*
X521493D03*
X516693Y41545D03*
X521493D03*
Y36745D03*
X516693D03*
X521493Y31945D03*
X526530Y43775D03*
X516693Y31945D03*
X567700Y28240D03*
X548550Y76480D03*
X525000Y76300D03*
X525200Y80900D03*
X556710Y64726D03*
X543750Y76480D03*
X506500Y76600D03*
X501500D03*
Y71600D03*
X608847Y34607D03*
X614032Y33307D03*
X621747Y63307D03*
X626647Y77507D03*
Y72507D03*
Y67507D03*
X593017Y69796D03*
X588217Y74596D03*
Y69796D03*
X576624Y193205D03*
Y198205D03*
Y203205D03*
Y208205D03*
Y213205D03*
Y223205D03*
Y228205D03*
Y233205D03*
Y238205D03*
Y243205D03*
Y248205D03*
Y253205D03*
Y258205D03*
Y263205D03*
Y268205D03*
Y273205D03*
Y278205D03*
Y333205D03*
Y338205D03*
Y343205D03*
Y348205D03*
Y353205D03*
Y358205D03*
Y363205D03*
Y368205D03*
Y373205D03*
Y378205D03*
Y383205D03*
Y388205D03*
Y393205D03*
Y398205D03*
Y403205D03*
Y408205D03*
Y413205D03*
Y418205D03*
Y423205D03*
Y428205D03*
Y433205D03*
Y438205D03*
Y443205D03*
Y448205D03*
Y498205D03*
Y503205D03*
Y508205D03*
Y513205D03*
Y518205D03*
Y523205D03*
Y528205D03*
Y533205D03*
Y538205D03*
Y543205D03*
Y548205D03*
Y553205D03*
Y558205D03*
Y563205D03*
Y568205D03*
Y573205D03*
Y578205D03*
Y583205D03*
Y588205D03*
X578710Y592712D03*
X580946Y597184D03*
X583182Y601656D03*
X585418Y606129D03*
X587654Y610601D03*
X635975Y621407D03*
X640975D03*
X715546Y8514D03*
X710546D03*
X705546D03*
X700546D03*
X695546D03*
X668847Y27107D03*
X663847D03*
X658847D03*
X653847D03*
X653601Y46761D03*
X658601D03*
X653601Y51761D03*
X658601D03*
X663601Y46761D03*
Y51761D03*
X668601Y46761D03*
Y51761D03*
X700065Y135985D03*
Y125985D03*
Y115985D03*
X710065D03*
Y125985D03*
Y135985D03*
X649590Y114036D03*
X700065Y155985D03*
X710065D03*
Y145985D03*
X696159Y225829D03*
X698909Y278104D03*
X700065Y265985D03*
Y255985D03*
Y245985D03*
Y235985D03*
X710065D03*
Y245985D03*
Y255985D03*
Y265985D03*
X709625Y275991D03*
X710065Y325985D03*
Y315985D03*
X711574Y285985D03*
X708307Y295429D03*
X710065Y305985D03*
Y335985D03*
Y345985D03*
X700065Y385985D03*
Y395985D03*
Y405985D03*
Y415985D03*
X710065Y375985D03*
Y355985D03*
Y365985D03*
Y455985D03*
X684399Y466984D03*
Y471984D03*
X663500Y484000D03*
Y489000D03*
Y494000D03*
X692282Y476720D03*
X689875Y464586D03*
X698275Y438305D03*
X683100Y485200D03*
X679832Y494100D03*
Y489100D03*
X679100Y483300D03*
X674900D03*
X674832Y489100D03*
Y494100D03*
X682800Y480700D03*
X693392Y520482D03*
X683392D03*
X688392D03*
X705080Y521247D03*
X694272Y495786D03*
X645975Y621407D03*
X650975D03*
X655975D03*
X660975D03*
X665975D03*
X670975D03*
X675975D03*
X680975D03*
X685975D03*
X690975D03*
X695975D03*
X700975D03*
X705975D03*
X710975D03*
X715975D03*
X785546Y8514D03*
X780546D03*
X775546D03*
X770546D03*
X765546D03*
X760546D03*
X755546D03*
X750546D03*
X745546D03*
X740546D03*
X735546D03*
X730546D03*
X725546D03*
X720546D03*
X770065Y55985D03*
Y65985D03*
Y75985D03*
X750065Y85985D03*
X770065D03*
X760065D03*
X740065D03*
X730065Y95985D03*
X760065D03*
X780065D03*
X770065D03*
Y105985D03*
X780065D03*
Y115985D03*
X730065Y135985D03*
Y125985D03*
Y115985D03*
Y105985D03*
X750065Y95985D03*
X740065D03*
X750065Y105985D03*
X760065D03*
X740065D03*
X750065Y115985D03*
X760065D03*
X770065D03*
X740065D03*
X750065Y125985D03*
X760065D03*
X770065D03*
X780065D03*
X740065D03*
X750065Y135985D03*
X760065D03*
X770065D03*
X780065D03*
X740065D03*
X720065Y105985D03*
Y115985D03*
Y125985D03*
Y135985D03*
Y155985D03*
X780065D03*
X730065D03*
Y145985D03*
X750065D03*
X760065D03*
X770065D03*
X780065D03*
X740065D03*
X750065Y155985D03*
X760065D03*
X770065D03*
X740065D03*
X750065Y165985D03*
X760065D03*
X770065D03*
X740065D03*
X750065Y175985D03*
X760065D03*
X770065D03*
X740065D03*
X750065Y185985D03*
X760065D03*
X770065D03*
X740065D03*
X750065Y195985D03*
X760065D03*
X770065D03*
X740065D03*
X750065Y205985D03*
X760065D03*
X770065D03*
X740065D03*
X720065Y145985D03*
X730065Y215985D03*
X773469Y277001D03*
X780065Y275985D03*
X787817Y275879D03*
X750065Y215985D03*
X760065D03*
X770065D03*
X780065D03*
X740065D03*
X780065Y265985D03*
Y255985D03*
Y245985D03*
Y235985D03*
Y225985D03*
X770065Y265985D03*
Y255985D03*
Y245985D03*
Y235985D03*
Y225985D03*
X763133Y275881D03*
X759790Y263326D03*
X760065Y255985D03*
Y245985D03*
Y235985D03*
Y225985D03*
X750065Y275985D03*
Y265985D03*
Y255985D03*
Y245985D03*
Y235985D03*
Y225985D03*
X741608Y277171D03*
X740065Y265985D03*
Y255985D03*
Y245985D03*
Y235985D03*
Y225985D03*
X730830Y276087D03*
X730065Y265985D03*
Y255985D03*
X731766Y246017D03*
X730065Y235985D03*
X730190Y223549D03*
X720237Y223228D03*
X720065Y235985D03*
X721766Y246017D03*
X720065Y255985D03*
Y265985D03*
X718617Y275736D03*
X770065Y335985D03*
X760065D03*
X720065Y325985D03*
X760065D03*
X750065D03*
X740065D03*
X730065D03*
X720065Y315985D03*
X780065Y285985D03*
X770065D03*
X760065D03*
X750065Y295985D03*
X760065D03*
X770065D03*
X780065D03*
Y305985D03*
Y315985D03*
Y325985D03*
Y335985D03*
Y345985D03*
X770065Y305985D03*
Y315985D03*
Y325985D03*
Y345985D03*
X760065Y305985D03*
Y315985D03*
Y345985D03*
X750065Y305985D03*
Y315985D03*
Y335985D03*
Y345985D03*
X740065Y305985D03*
Y315985D03*
Y335985D03*
Y345985D03*
X730065D03*
Y335985D03*
Y315985D03*
X752500Y286000D03*
X740065Y295985D03*
X741000Y286000D03*
X730065Y305985D03*
X729486Y296094D03*
X729294Y285987D03*
X721574Y285985D03*
X719049Y296011D03*
X720065Y305985D03*
Y335985D03*
Y345985D03*
X750065Y415985D03*
X760065D03*
X770065D03*
X780065D03*
X730065D03*
X740065D03*
X750065Y405985D03*
X760065D03*
X770065D03*
X780065D03*
X730065D03*
X740065D03*
X780065Y395985D03*
X770065D03*
X760065D03*
X750065D03*
X740065D03*
X730065D03*
X720065Y375985D03*
X730065Y365985D03*
Y375985D03*
Y385985D03*
X750065D03*
X760065D03*
X770065D03*
X780065D03*
X740065D03*
X750065Y375985D03*
X760065D03*
X770065D03*
X780065D03*
X740065D03*
X750065Y365985D03*
X760065D03*
X770065D03*
X780065D03*
X740065D03*
X780065Y355985D03*
X770065D03*
X760065D03*
X750065D03*
X740065D03*
X730065D03*
X720065D03*
Y365985D03*
Y455985D03*
Y465985D03*
X750065D03*
X760065D03*
X770065D03*
X780065D03*
X730065D03*
X740065D03*
X780065Y455985D03*
X770065D03*
X760065D03*
X750065D03*
X740065D03*
X730065D03*
X750065Y445985D03*
X760065D03*
X770065D03*
X780065D03*
X730065D03*
X740065D03*
X750065Y435985D03*
X760065D03*
X770065D03*
X780065D03*
X740065D03*
X750065Y425985D03*
X760065D03*
X770065D03*
X780065D03*
X736217Y493664D03*
X776658Y489380D03*
X771658D03*
X781658D03*
Y494380D03*
X741217Y493664D03*
X776658Y494380D03*
X771658D03*
X784604Y519082D03*
X758512Y534430D03*
X747107Y536580D03*
X739334Y524156D03*
X752602Y517850D03*
X736580Y507734D03*
X788015Y507785D03*
X783015D03*
X747602Y517850D03*
X731580Y507734D03*
X716578Y509762D03*
X721590Y511659D03*
X726590D03*
X720975Y621407D03*
X725975D03*
X730975D03*
X735975D03*
X740975D03*
X745975D03*
X750975D03*
X755975D03*
X760975D03*
X765975D03*
X770975D03*
X775975D03*
X780975D03*
X785975D03*
X850546Y8514D03*
X845546D03*
X840546D03*
X835546D03*
X830546D03*
X825546D03*
X820546D03*
X815546D03*
X810546D03*
X805546D03*
X800546D03*
X795546D03*
X790546D03*
X820065Y105985D03*
Y135985D03*
Y125985D03*
Y115985D03*
X810065Y135985D03*
Y125985D03*
Y115985D03*
X790065Y105985D03*
X800065Y115985D03*
X790065D03*
Y125985D03*
X800065D03*
Y135985D03*
X790065D03*
X853436Y108917D03*
Y113717D03*
X853435Y90260D03*
Y95060D03*
X820065Y155985D03*
X810065D03*
X800065D03*
X790065D03*
X820065Y145985D03*
X810065D03*
X790065D03*
X800065D03*
X820313Y276188D03*
X810065Y275985D03*
X800065D03*
X820065Y265985D03*
Y255985D03*
Y245985D03*
Y235985D03*
Y225985D03*
X810065Y265985D03*
Y255985D03*
Y245985D03*
Y235985D03*
X800065Y265985D03*
Y255985D03*
Y245985D03*
Y235985D03*
X790065Y265985D03*
Y255985D03*
Y245985D03*
Y235985D03*
Y225985D03*
X857965Y273150D03*
X820065Y305985D03*
Y295985D03*
Y285985D03*
X810065Y295985D03*
Y285985D03*
X800065D03*
X790065D03*
Y295985D03*
X800065D03*
X810065Y305985D03*
X810000Y314000D03*
X810065Y325985D03*
X800065Y305985D03*
Y315985D03*
Y325985D03*
Y335985D03*
Y345985D03*
X790065Y305985D03*
Y315985D03*
Y325985D03*
X791500Y336000D03*
X790065Y345985D03*
X859407Y300314D03*
Y309914D03*
Y305114D03*
Y295314D03*
Y290314D03*
Y285314D03*
X790065Y415985D03*
Y405985D03*
Y395985D03*
Y375985D03*
X800065D03*
X790065Y365985D03*
X800065D03*
Y355985D03*
X790065D03*
X800065Y455985D03*
Y465985D03*
X790065D03*
Y455985D03*
Y445985D03*
Y435985D03*
X790191Y426486D03*
X809000Y429400D03*
X840057Y494320D03*
X835057D03*
X805771Y518743D03*
X789604Y519082D03*
X794604D03*
X836023Y508124D03*
X825161Y507954D03*
X820161D03*
X815161D03*
X805983Y508293D03*
X793015Y507785D03*
X790975Y621407D03*
X795975D03*
X800975D03*
X805975D03*
X810975D03*
X815975D03*
X820975D03*
X825975D03*
X830975D03*
X835975D03*
X840975D03*
X854971Y637313D03*
Y642313D03*
Y647313D03*
Y652313D03*
Y657313D03*
Y662313D03*
Y667313D03*
Y672313D03*
Y677313D03*
Y682313D03*
Y687313D03*
Y692313D03*
Y697313D03*
Y702313D03*
Y707313D03*
Y712313D03*
X916683Y62377D03*
Y57377D03*
Y52377D03*
Y47377D03*
Y42377D03*
Y37377D03*
Y32377D03*
Y27377D03*
Y22377D03*
Y17377D03*
X915546Y8514D03*
X910546D03*
X905546D03*
X900546D03*
X883222Y59214D03*
X888022D03*
X892822D03*
X897622D03*
X880922Y63714D03*
X885722D03*
X890522D03*
X895322D03*
X900122D03*
X916683Y132377D03*
Y127377D03*
Y122377D03*
Y117377D03*
Y112377D03*
Y107377D03*
Y102377D03*
Y97377D03*
Y92377D03*
Y87377D03*
Y82377D03*
Y77377D03*
Y72377D03*
Y67377D03*
X897250Y81510D03*
X902050D03*
Y86310D03*
X897250D03*
Y91110D03*
X902050D03*
X897250Y95910D03*
X902050D03*
X916683Y207377D03*
Y202377D03*
Y197377D03*
Y192377D03*
Y187377D03*
Y182377D03*
Y177377D03*
Y172377D03*
Y167377D03*
Y162377D03*
Y157377D03*
Y152377D03*
Y147377D03*
Y142377D03*
Y137377D03*
X900600Y201239D03*
X897803Y207684D03*
X902803D03*
X880222Y206781D03*
X875222D03*
X916683Y277377D03*
Y272377D03*
Y267377D03*
Y262377D03*
Y257377D03*
Y252377D03*
Y247377D03*
Y242377D03*
Y237377D03*
Y232377D03*
Y227377D03*
Y222377D03*
Y217377D03*
Y212377D03*
X897195Y275688D03*
X902195D03*
Y270688D03*
X897195D03*
X897803Y217684D03*
Y212684D03*
X902803Y217684D03*
Y212684D03*
X896031Y228468D03*
Y223468D03*
X891031D03*
Y228468D03*
Y238468D03*
X896031D03*
X891031Y233468D03*
X896031D03*
X868376Y271313D03*
X873376D03*
X880122Y216781D03*
X875122D03*
X880222Y211781D03*
X875222D03*
X916683Y347377D03*
Y342377D03*
Y337377D03*
Y332377D03*
Y327377D03*
Y322377D03*
Y317377D03*
Y312377D03*
Y307377D03*
Y302377D03*
Y297377D03*
Y292377D03*
Y287377D03*
Y282377D03*
X896030Y296330D03*
X901030D03*
X900995Y290712D03*
X895995D03*
X900819Y316367D03*
X895819D03*
X900716Y311058D03*
X895716D03*
X864207Y300314D03*
Y309914D03*
Y305114D03*
Y295314D03*
Y290314D03*
Y285314D03*
X916683Y422377D03*
Y417377D03*
Y412377D03*
Y407377D03*
Y402377D03*
Y397377D03*
Y392377D03*
Y387377D03*
Y382377D03*
Y377377D03*
Y372377D03*
Y367377D03*
Y362377D03*
Y357377D03*
Y352377D03*
X876451Y407949D03*
X880665Y410841D03*
X885665D03*
X890665D03*
X895665D03*
X900665D03*
X902091Y369397D03*
X897091D03*
X902091Y374397D03*
X897091D03*
Y379397D03*
X902091D03*
X888548Y392923D03*
X883548D03*
X893548D03*
X888548Y387923D03*
X893548D03*
X883548D03*
X916683Y492377D03*
Y487377D03*
Y482377D03*
Y477377D03*
Y472377D03*
Y467377D03*
Y462377D03*
Y457377D03*
Y452377D03*
Y447377D03*
Y442377D03*
Y437377D03*
Y432377D03*
Y427377D03*
Y562377D03*
Y557377D03*
Y552377D03*
Y547377D03*
Y542377D03*
Y537377D03*
Y532377D03*
Y527377D03*
Y522377D03*
Y517377D03*
Y512377D03*
Y507377D03*
Y502377D03*
Y497377D03*
Y637377D03*
Y632377D03*
Y627377D03*
Y622377D03*
Y617377D03*
Y612377D03*
Y607377D03*
Y602377D03*
Y597377D03*
Y592377D03*
Y587377D03*
Y582377D03*
Y577377D03*
Y572377D03*
Y567377D03*
Y707377D03*
Y702377D03*
Y697377D03*
Y692377D03*
Y687377D03*
Y682377D03*
Y677377D03*
Y672377D03*
Y667377D03*
Y662377D03*
Y657377D03*
Y652377D03*
Y647377D03*
Y642377D03*
X901041Y753684D03*
X903277Y749212D03*
X905513Y744740D03*
X907749Y740268D03*
X909985Y735796D03*
X912221Y731323D03*
X914457Y726851D03*
X916683Y722377D03*
Y717377D03*
Y712377D03*
X1105450Y697125D03*
G54D20*
X168898Y548819D03*
X184645Y539370D03*
X194094D03*
X203542Y545671D03*
X197243Y539371D03*
X194093Y564569D03*
X190944D03*
X194093Y555120D03*
X184646D03*
X153149Y536221D03*
X165748Y558268D03*
X172048Y555120D03*
X156297Y558267D03*
X187925Y564617D03*
X168898Y561417D03*
X206692Y555120D03*
X165745Y564567D03*
X168895D03*
X159449Y561417D03*
X165748D03*
X172047D03*
X162598Y558268D03*
X168898D03*
X165748Y555118D03*
X159449D03*
X162599Y551970D03*
X194093D03*
X197243D03*
X181497D03*
X175197D03*
X178347D03*
X203542Y555120D03*
X187795D03*
X200393Y551970D03*
X206692Y558269D03*
Y561419D03*
Y564569D03*
X175196Y558269D03*
X190945Y545669D03*
X172047D03*
Y551970D03*
X159449Y545671D03*
X162599Y545669D03*
X165749D03*
X212991Y561419D03*
X184646Y548821D03*
Y545671D03*
X184645Y542519D03*
X206693Y542520D03*
X159449Y542521D03*
X171906Y534661D03*
X212991Y542519D03*
X156299Y545671D03*
X165749Y548819D03*
X175197Y545671D03*
X162599Y542519D03*
X168898D03*
X156299Y542521D03*
X181496Y542520D03*
X159449Y548821D03*
X194094Y542519D03*
X172047Y548819D03*
X168898Y551969D03*
X162599Y548821D03*
X162598Y561417D03*
X168898Y555119D03*
X181497Y548821D03*
X178346Y545670D03*
X181497Y545671D03*
X162595Y564567D03*
X203542Y551970D03*
X181497Y555120D03*
X178346Y555119D03*
X187885Y552058D03*
X197245Y555118D03*
X159412Y552006D03*
X165748Y551968D03*
X178347Y564569D03*
X203543Y561418D03*
Y564568D03*
X172047D03*
X200393Y548819D03*
X209842Y545669D03*
Y564567D03*
Y558268D03*
X212992Y551969D03*
Y548819D03*
X209842Y561417D03*
X212992Y564567D03*
X200393Y545669D03*
X206692Y545671D03*
X209842Y548819D03*
X212992Y545669D03*
X165777Y542555D03*
X209842Y555119D03*
Y551969D03*
X206692Y548820D03*
X206693Y551969D03*
X194094Y545669D03*
Y548820D03*
X175197Y548821D03*
X168898Y545669D03*
X153150Y539371D03*
X153149Y542521D03*
X197244Y545669D03*
Y542519D03*
X156300Y539371D03*
X197243Y589900D03*
X194094Y602362D03*
X206692Y596063D03*
X203450Y592912D03*
X194093Y596063D03*
X172020Y577050D03*
X175196Y589764D03*
X190944Y577166D03*
X194093Y574016D03*
Y567718D03*
X190944Y574016D03*
Y567718D03*
X187795Y577166D03*
X184646D03*
X172048Y589764D03*
X168898D03*
X187844Y574065D03*
X184645Y574166D03*
X187746Y567669D03*
X184695Y567666D03*
X184646Y570867D03*
X168898Y570866D03*
X156299Y586614D03*
Y580315D03*
X159449Y567717D03*
X156299Y570866D03*
X200393Y589764D03*
X187900Y589800D03*
X187794Y586614D03*
X203542Y589764D03*
X200393Y596063D03*
X187795Y592914D03*
X203605Y605821D03*
X187795Y602363D03*
X153149Y605513D03*
X206692Y592913D03*
X165748Y583464D03*
X209842D03*
X212992Y586614D03*
X212991Y567718D03*
X209841Y574016D03*
X206692D03*
X168898Y567717D03*
X159449Y570866D03*
X168898Y583464D03*
Y577165D03*
X159449Y586614D03*
X162598Y580315D03*
Y586614D03*
X165748D03*
X168898D03*
X159449Y577165D03*
X156299D03*
X168898Y580315D03*
X159449D03*
X162598Y577165D03*
X165748Y580315D03*
X162598Y583464D03*
X165748Y570866D03*
Y567717D03*
X162598D03*
X172047Y570867D03*
X194094Y577166D03*
X203543Y574017D03*
X178347Y589764D03*
X181497D03*
X194093Y586614D03*
X209841Y596063D03*
X206692Y583465D03*
Y567600D03*
X212992Y580315D03*
X212991Y577165D03*
X209842Y567717D03*
X212991Y574016D03*
X190945Y599213D03*
X190944Y596063D03*
X187796Y599212D03*
X181586Y599123D03*
X212991Y583465D03*
X209841Y577165D03*
X159448Y596063D03*
X190944Y602362D03*
X203543D03*
X203542Y596063D03*
X194094Y599213D03*
X168898Y596063D03*
X212992Y602363D03*
X212991Y599212D03*
X206692Y589763D03*
X168898Y592913D03*
X162598Y596063D03*
X194093Y589764D03*
Y592913D03*
X206692Y586614D03*
X209842Y586613D03*
X212992Y589764D03*
X209841Y592913D03*
X162598Y570866D03*
X178347Y574018D03*
X203542Y580315D03*
Y586614D03*
X190944D03*
X178346Y586615D03*
X181497Y586614D03*
X178344Y577166D03*
X203542Y577165D03*
X178347Y570769D03*
X203501Y571005D03*
X175298Y577266D03*
X172047Y567717D03*
X178346Y596064D03*
X178347Y599213D03*
X165748D03*
X168898D03*
X162598D03*
X159448D03*
X172048Y596063D03*
X190944Y592913D03*
Y589764D03*
X200393Y586614D03*
X197165Y586540D03*
X212993Y592912D03*
X209842Y589763D03*
X206692Y580315D03*
X209841D03*
X181500Y595900D03*
X200393Y592912D03*
X209841Y599212D03*
X200393D03*
X159448Y589764D03*
Y592913D03*
X162598Y589764D03*
X165748D03*
Y596063D03*
Y592913D03*
X175197D03*
X172048D03*
X181530Y592765D03*
X175197Y596063D03*
Y599213D03*
X172048D03*
X216141Y564569D03*
Y561419D03*
X219291Y542519D03*
X216141D03*
X216142Y548820D03*
X216141Y555120D03*
Y558269D03*
X222441Y548820D03*
X219291D03*
X216141Y551970D03*
X216142Y545669D03*
X216141Y580315D03*
X222440Y605512D03*
X216141Y577165D03*
Y583465D03*
Y586614D03*
Y567718D03*
X219293Y567717D03*
X216141Y574016D03*
Y599212D03*
Y589762D03*
X230600Y608100D03*
X355600Y172900D03*
X363400Y115950D03*
X815600Y386200D03*
X1105450Y867225D03*
G54D30*
X488838Y137225D03*
X1105450Y300225D03*
G54D21*
X201801Y684252D03*
X225601D03*
X1105450Y498675D03*
G54D12*
X43000Y59500D03*
X51000D03*
X34000Y59400D03*
X38500Y56500D03*
X46500Y48500D03*
X28123Y453658D03*
X62276Y550493D03*
X37660Y566400D03*
X64427Y538836D03*
X67853Y558117D03*
X64701Y564416D03*
X28782Y555119D03*
X34132Y521245D03*
X34175Y526969D03*
X29165Y532612D03*
X29058Y538228D03*
X29158Y543855D03*
X28800Y549474D03*
X33697Y560866D03*
X61100Y546700D03*
X64277Y502177D03*
X67852Y539219D03*
X67853Y564416D03*
Y554967D03*
Y542368D03*
X64701Y561266D03*
X63456Y555041D03*
X67853Y561266D03*
X64701Y542366D03*
X64151Y521695D03*
X53524Y521269D03*
Y526995D03*
Y532622D03*
X52613Y538242D03*
X52408Y543876D03*
X52603Y549526D03*
X52485Y555153D03*
X53300Y560879D03*
X42597Y571789D03*
X67852Y583313D03*
X67853Y573865D03*
X67852Y586463D03*
X64701Y570716D03*
X67853Y577015D03*
X64703Y586463D03*
X64701Y567566D03*
X67853Y570715D03*
X53302Y567317D03*
X58926Y582407D03*
X28667Y634097D03*
X42550Y599224D03*
X50400Y663700D03*
X50500Y667900D03*
X64884Y650984D03*
X37961Y659909D03*
X41100Y671800D03*
X56100Y676000D03*
X86268Y58755D03*
X90768Y69755D03*
X82768D03*
X73768Y69655D03*
X78268Y66755D03*
X121233Y450900D03*
X104000Y475500D03*
X118197Y490300D03*
X108500Y475500D03*
X97074Y492891D03*
X112722Y493971D03*
X98400Y473200D03*
X140490Y488605D03*
X132777Y462639D03*
X130787Y479138D03*
X113300Y448564D03*
X118065Y448535D03*
X100600Y490750D03*
X138023Y456188D03*
X140985Y454250D03*
X135262Y475726D03*
X105350Y511850D03*
X89899Y564415D03*
X119400Y511500D03*
X135012Y510200D03*
X94473Y547093D03*
X106272Y547370D03*
X89899Y558115D03*
X138900Y525999D03*
X136974Y534479D03*
X120500Y504600D03*
X69904Y502077D03*
X75399Y502179D03*
X81094Y502166D03*
X86699Y502300D03*
X97926D03*
X74151Y545516D03*
X86750Y542368D03*
X126337Y554085D03*
X74498Y551757D03*
X130311Y546700D03*
X71002Y539219D03*
X81276Y548766D03*
X119605Y548705D03*
X86750Y539218D03*
X74076Y535966D03*
X83600Y545518D03*
X75508Y542198D03*
X89899Y545518D03*
X127300Y543200D03*
X71002Y542368D03*
X117200Y546300D03*
X89899Y539218D03*
X83600Y539219D03*
X71002Y545518D03*
X86750D03*
X122600Y557480D03*
X71002Y558117D03*
X86750Y554965D03*
Y558115D03*
X83600Y551817D03*
X71002Y564396D03*
Y561266D03*
X83600Y564415D03*
X86750D03*
X75066Y563235D03*
X83600Y561265D03*
X71002Y554967D03*
X86750Y551815D03*
X123300Y530300D03*
X119400Y521700D03*
X133800Y528500D03*
X102601Y507300D03*
X123200Y534600D03*
X78276Y545566D03*
X93744Y542019D03*
X133554Y537374D03*
X71002Y548668D03*
X92600Y535623D03*
X86750Y561265D03*
X89899D03*
X94720Y557158D03*
X92286Y521695D03*
X86659D03*
X81032D03*
X75405D03*
X69778D03*
X97913D03*
X96371Y534124D03*
X125400Y498600D03*
X140400Y607850D03*
X137000D03*
X130700D03*
X135706Y621187D03*
X119900Y621000D03*
X131200Y620600D03*
X108371Y577258D03*
X86750Y567565D03*
X89901Y587466D03*
X93048Y577014D03*
X86750Y573864D03*
X89899D03*
X71002Y577013D03*
X85400Y629784D03*
X75197Y572437D03*
X130607Y569636D03*
X126347Y569556D03*
X117400Y567650D03*
X83600Y573865D03*
X74152Y567565D03*
X86750Y586463D03*
X71002Y567565D03*
X86750Y583313D03*
X74152Y580163D03*
X83601Y580164D03*
X89899Y577014D03*
X74152Y577013D03*
X86750Y577014D03*
X96570Y581730D03*
X118900Y609900D03*
X116400Y626600D03*
X124903Y613900D03*
X124793Y617299D03*
X139500Y611200D03*
X74152Y583312D03*
X94011Y597066D03*
X101608Y596523D03*
X93048Y580164D03*
X89899Y567565D03*
X93049Y573864D03*
X93051Y587466D03*
X83600Y567565D03*
X103098Y620264D03*
X98537Y601094D03*
X102509Y601100D03*
X103109Y608572D03*
X103124Y605153D03*
X103098Y612064D03*
Y624364D03*
X113400Y617400D03*
X70700Y629000D03*
X127100Y647000D03*
X123100D03*
X119000D03*
X73427Y699285D03*
X104550Y647050D03*
X104850Y639150D03*
X111300Y705500D03*
X86028Y696439D03*
X81928Y697539D03*
X106879Y707245D03*
X125376Y701124D03*
X106635Y701465D03*
X94106Y699683D03*
X131300Y650100D03*
X135000Y650000D03*
X89868Y689124D03*
X121300Y651900D03*
X139774Y666686D03*
X119849Y709715D03*
X106355Y710745D03*
X148000Y469000D03*
X196100Y482200D03*
X170870Y492270D03*
X186254Y463761D03*
X143700Y469000D03*
X188708Y468154D03*
X175115Y463761D03*
X167821Y488301D03*
X208370Y491570D03*
X200260Y465900D03*
X211324Y489886D03*
X167656Y465300D03*
X189700Y463500D03*
X181200Y489451D03*
X155710Y485200D03*
X172300Y478400D03*
X172900Y484101D03*
X169252Y483871D03*
X213159Y460326D03*
X154334Y465100D03*
X149000Y488600D03*
X171537Y464400D03*
X201600Y486500D03*
X198200D03*
X190036Y485520D03*
X163031Y441700D03*
X153489Y481559D03*
X148490Y451286D03*
X144245Y452344D03*
X151877Y450439D03*
X155877D03*
X145000Y488600D03*
X166761Y498900D03*
X198700Y513500D03*
X203350Y506700D03*
X188600Y531500D03*
X179000Y499800D03*
X203500Y513500D03*
X191398Y509000D03*
X211700Y513500D03*
X208700Y529100D03*
X207500Y502412D03*
X145000Y497600D03*
X187500Y523700D03*
X154730Y512704D03*
X158241Y512675D03*
X170700Y513600D03*
X182870Y513832D03*
X212300Y529000D03*
X141980Y508590D03*
X146900Y512500D03*
X185615Y498015D03*
X174900Y499800D03*
X203610Y529397D03*
X179400Y525100D03*
X182964Y510414D03*
X154400Y533500D03*
X187100Y509600D03*
X195200Y513200D03*
X162537Y499000D03*
X160286Y508429D03*
X143415Y530143D03*
X171200Y509840D03*
X170800Y499800D03*
X166600Y524100D03*
X144087Y526413D03*
X174717Y524010D03*
X178869Y509793D03*
X200650Y497862D03*
X199501Y509275D03*
X191200Y522500D03*
X191300Y525900D03*
X174700Y509600D03*
X207500Y505812D03*
X158000Y499000D03*
X200200Y529200D03*
X156000Y496100D03*
X203696Y533000D03*
X156200Y535800D03*
X188834Y496920D03*
X150553Y512500D03*
X148050Y523740D03*
X196800Y497862D03*
X193200Y497000D03*
X174400Y519283D03*
X200963Y636600D03*
X212923Y615000D03*
X191210Y617900D03*
X203300Y628900D03*
X148409Y575672D03*
X144876Y590854D03*
X148409Y579353D03*
X144876Y587173D03*
X185100Y614300D03*
X179700Y615300D03*
X151800Y615400D03*
X174799Y630303D03*
X171400Y630200D03*
X199950Y614000D03*
X196100Y614050D03*
X203900Y614100D03*
X144737Y630882D03*
X200100Y633300D03*
X209193Y614249D03*
X162750Y612217D03*
X164400Y609200D03*
X182100Y629800D03*
X178200D03*
X141742Y624666D03*
X144263Y609023D03*
X151800Y610300D03*
X188899Y629597D03*
X185500Y629700D03*
X154500Y629600D03*
X195600Y646000D03*
X166500Y640300D03*
X191766Y679920D03*
X211706Y645349D03*
X208200Y645500D03*
X148249Y695765D03*
X151130Y703440D03*
X184807Y643963D03*
X188500Y686800D03*
X205827Y695000D03*
X188600Y696800D03*
X159058Y641132D03*
X142572Y640332D03*
X150872D03*
X177100Y640400D03*
X173000D03*
X193400Y639700D03*
X189500D03*
X185300D03*
X181000D03*
X198700D03*
X151949Y691715D03*
X176447Y704925D03*
X162700Y703500D03*
X162360Y706888D03*
X168273Y696434D03*
X158994Y694545D03*
X205800Y698400D03*
X210123Y662100D03*
X200000Y664200D03*
X204100Y646500D03*
X199600Y646300D03*
X195500Y696900D03*
X207000Y654400D03*
X185598Y709274D03*
X182200Y709400D03*
X143174Y666586D03*
X162100Y711215D03*
X275276Y494017D03*
X213900Y474650D03*
X227100Y490300D03*
X275300Y467300D03*
X275700Y490300D03*
X275100Y472400D03*
X264800Y467400D03*
X278800Y467500D03*
X277455Y446150D03*
X226475Y480400D03*
X254100Y440800D03*
X257950Y440600D03*
X226500Y477000D03*
X275113Y476513D03*
X266664Y493000D03*
X214808Y463300D03*
X231400Y489800D03*
X237903D03*
X267670Y485870D03*
X271100Y485900D03*
X222995Y443805D03*
X280600Y448900D03*
X214900Y490000D03*
X231476Y449662D03*
X276591Y483709D03*
X245874Y458478D03*
X242500Y458900D03*
X253400Y453500D03*
X273400Y449700D03*
X249465Y458000D03*
X252626Y469150D03*
X244400Y478600D03*
X244300Y474150D03*
X225532Y450047D03*
X237600Y455500D03*
X233664Y482859D03*
X226607Y444058D03*
X230610Y444055D03*
X234648Y540453D03*
X221960Y504230D03*
X222500Y536161D03*
X279600Y527900D03*
X272100Y537500D03*
X251346Y554100D03*
X256816Y563982D03*
X262996Y548757D03*
X231450Y563000D03*
X270021Y549394D03*
X283600Y539294D03*
X242700Y548600D03*
X252400Y539600D03*
X271715Y556690D03*
X263400Y531500D03*
X233850Y552201D03*
X234943Y565199D03*
X265100Y562300D03*
X227600Y563000D03*
X254494Y529198D03*
X248459Y523892D03*
X269100Y509063D03*
X244850Y540150D03*
X248700Y540000D03*
X228200Y496200D03*
X263600Y540700D03*
X226357Y504514D03*
X257894Y529254D03*
X263600Y535350D03*
X223800Y531600D03*
X236400Y502150D03*
X246508Y532821D03*
X228100Y545500D03*
X227100Y525400D03*
X228800Y542100D03*
X238600Y509900D03*
X228313Y552169D03*
X233100Y509800D03*
X275100D03*
X260900Y553900D03*
X242600Y509800D03*
X233607Y557671D03*
X241154Y536017D03*
X250445Y548551D03*
X255800Y539600D03*
X279200Y531600D03*
X250400Y636976D03*
X215800Y631200D03*
X260705Y598359D03*
X232896Y613795D03*
X279450Y577970D03*
X260850Y603537D03*
X274800Y607500D03*
X258600Y613100D03*
X254208Y603995D03*
X254043Y598359D03*
X247088Y610236D03*
X254821Y627000D03*
X255228Y631071D03*
X278150Y637250D03*
X229800Y593200D03*
X246800Y589600D03*
X261900Y588900D03*
X245400Y581800D03*
X264358Y608152D03*
X241300Y635900D03*
X228900Y635800D03*
X222500Y630200D03*
X218800Y635600D03*
X225900Y615000D03*
X221800Y614800D03*
X246500Y602500D03*
X234000Y628400D03*
X230900Y581600D03*
X270300Y622315D03*
X281500Y598419D03*
X231200Y576800D03*
X234700Y581600D03*
X254408Y586483D03*
X255400Y579500D03*
X225900Y630988D03*
X230063Y618667D03*
X274100Y591000D03*
X279745Y608000D03*
X255663Y617763D03*
X276376Y574132D03*
X281636Y588796D03*
X231000Y571900D03*
X242333Y593800D03*
X257346Y599169D03*
X257332Y602569D03*
X258398Y605915D03*
Y609484D03*
X218200Y609500D03*
X262694Y568076D03*
X261300Y571300D03*
X235800Y615100D03*
X233447Y603747D03*
X232300Y600300D03*
X258596Y586356D03*
X259848Y583194D03*
X279214Y591383D03*
X275652Y577455D03*
X237100Y590000D03*
X234087Y618038D03*
X248800Y582000D03*
X273022Y580751D03*
X268200Y578700D03*
X259000Y617000D03*
X234800Y572000D03*
X256007Y575050D03*
X281975Y572963D03*
X279800Y569182D03*
X264200Y574100D03*
X261810Y633980D03*
X264800Y632300D03*
X276783Y588907D03*
X258873Y631373D03*
X215400Y626800D03*
X281510Y583003D03*
X276400Y700650D03*
X254900Y701950D03*
X267500Y645600D03*
X280500Y708100D03*
X269003Y704337D03*
X282620Y640950D03*
X262826Y662274D03*
X245100Y639500D03*
X219200Y645300D03*
X230270Y645933D03*
X247725Y656375D03*
X261900Y699300D03*
X266550Y675750D03*
X247825Y670375D03*
X245971Y698400D03*
X235100Y679921D03*
X221575Y695400D03*
X279400Y686400D03*
X223013Y645672D03*
X231500Y659100D03*
X255050Y675750D03*
X271240Y698960D03*
X243731Y709100D03*
X272900Y669100D03*
X254600Y685100D03*
X278150Y648363D03*
X284000Y678300D03*
X263800Y648902D03*
X236000Y646100D03*
X272300Y665700D03*
X266398Y679250D03*
X226708Y645869D03*
X239400Y677600D03*
X267045Y695881D03*
X215606Y645300D03*
X217638Y695562D03*
X239000Y691000D03*
X276400Y697250D03*
X254700Y708900D03*
X271220Y679910D03*
X255000Y679900D03*
X235042Y656173D03*
X263500Y643212D03*
X243100Y677500D03*
X267100Y699700D03*
X266400Y662200D03*
X280600Y711700D03*
X282353Y740020D03*
X268820Y715100D03*
X262645Y712155D03*
X254648Y745463D03*
X268520Y719420D03*
X258431Y712169D03*
X268230Y723570D03*
X345069Y108533D03*
X340080Y108432D03*
X348900Y115400D03*
X340706Y128612D03*
X352000Y109000D03*
X355500D03*
X305703Y202696D03*
X306407Y206057D03*
X355300Y179300D03*
X354282Y187718D03*
Y191718D03*
X305651Y199283D03*
X294720Y182200D03*
X320700Y177800D03*
X294720Y178600D03*
Y185600D03*
X307567Y277592D03*
Y273592D03*
X304548Y272508D03*
Y268508D03*
Y265008D03*
Y261008D03*
X321432Y279090D03*
X321281Y266486D03*
X321197Y254433D03*
X306446Y247874D03*
X323842Y219284D03*
X305498Y213824D03*
X305382Y227474D03*
X323800Y227000D03*
X323700Y230600D03*
X335100Y228117D03*
X333882Y273978D03*
Y270578D03*
X335098Y233078D03*
X305782Y230874D03*
X334482Y263778D03*
X333782Y267178D03*
X324000Y222800D03*
X305782Y220674D03*
X305682Y224074D03*
X305782Y217274D03*
X334198Y248824D03*
X305454Y244461D03*
X334282Y252378D03*
X305373Y251101D03*
X306412Y254339D03*
X334260Y255820D03*
X305882Y234274D03*
X305772Y237673D03*
X305781Y241076D03*
X334107Y291354D03*
Y287354D03*
Y283854D03*
Y279854D03*
X307567Y349192D03*
X304267Y348092D03*
Y344092D03*
Y340592D03*
Y336592D03*
X307567Y335492D03*
Y331492D03*
Y327992D03*
Y323992D03*
X304267Y322892D03*
Y318892D03*
Y315392D03*
Y311392D03*
X307567Y310292D03*
Y306292D03*
Y302792D03*
Y298792D03*
X304267Y297692D03*
Y293692D03*
Y290192D03*
Y286192D03*
X334582Y341721D03*
Y337721D03*
Y334221D03*
Y330221D03*
X328187Y350316D03*
Y346816D03*
Y342816D03*
X328182Y329124D03*
Y325124D03*
Y321624D03*
Y317624D03*
X334593Y316584D03*
Y312584D03*
Y309084D03*
Y305084D03*
X328182Y303977D03*
Y299977D03*
Y296477D03*
Y292477D03*
X307567Y285092D03*
Y281092D03*
X321432Y342082D03*
Y329484D03*
Y316885D03*
X321882Y304374D03*
Y291874D03*
X304267Y373292D03*
Y369292D03*
Y365792D03*
Y361792D03*
X307567Y360692D03*
Y356692D03*
Y353192D03*
X328182Y379518D03*
Y375518D03*
Y372018D03*
Y368018D03*
X334582Y366974D03*
Y362974D03*
Y359474D03*
Y355474D03*
X328187Y354316D03*
X320832Y367479D03*
X321432Y354681D03*
X320932Y377074D03*
X340606Y389899D03*
X336000Y384400D03*
X336230Y377800D03*
X350408Y393708D03*
X348006Y391300D03*
X321859Y388315D03*
X321100Y384874D03*
X346300Y374600D03*
X349100Y379100D03*
X303900Y380574D03*
X348997Y491678D03*
X295700Y428400D03*
X344900Y442800D03*
X344688Y493896D03*
X343050Y438900D03*
X339900Y454000D03*
X328313Y435513D03*
X324916Y435360D03*
X321700Y436650D03*
X296254Y546706D03*
X305350Y514300D03*
X292200Y542473D03*
X285800Y549394D03*
X346440Y527500D03*
X350879Y520400D03*
X352734Y541826D03*
X355700Y510000D03*
X344600Y511800D03*
X326900Y507700D03*
X304800Y554443D03*
X318200Y522900D03*
X285833Y557629D03*
X302700Y551300D03*
X339062Y521100D03*
X344600Y507600D03*
X341300Y536200D03*
X352921Y536521D03*
X311900Y514900D03*
X287500Y518000D03*
X297850Y524500D03*
X293600Y518400D03*
X313300Y518800D03*
X354300Y500245D03*
X288311Y496200D03*
X355600Y506600D03*
X298200Y521100D03*
X301300Y524400D03*
X355600Y513500D03*
X327300Y540100D03*
X341400Y560050D03*
X307800Y546700D03*
X341615Y556015D03*
X305913Y549643D03*
X331900Y549700D03*
X329050Y552315D03*
X348220Y563836D03*
X344812Y563844D03*
X344755Y497841D03*
X304436Y564081D03*
X341349Y563750D03*
X307350Y561290D03*
X335000Y497000D03*
X332698Y543738D03*
X330200Y535200D03*
X331000Y522100D03*
X302665Y547006D03*
X302506Y543341D03*
X327403Y543499D03*
X336723Y542000D03*
X327800Y514900D03*
X330200Y531800D03*
X323400Y507540D03*
X336800Y506300D03*
X286061Y502378D03*
X293970Y564927D03*
X335000Y500600D03*
X298719Y542538D03*
X293500Y522600D03*
X334811Y551476D03*
X311900Y511500D03*
X309600Y520150D03*
X312300Y540600D03*
X332940Y539287D03*
X333400Y503800D03*
X322900Y530600D03*
X327417Y548344D03*
X290000Y503200D03*
X293800Y503300D03*
X299100Y589200D03*
X304124Y570227D03*
X341750Y630790D03*
X342330Y620300D03*
X344940Y617720D03*
X292400Y637000D03*
X341690Y609930D03*
X341210Y602420D03*
X330800Y602610D03*
X317572Y603183D03*
X305470Y623734D03*
X307542Y588138D03*
X334923Y579949D03*
X353500Y624500D03*
X353669Y600881D03*
X302300Y582000D03*
X286700Y611911D03*
X340920Y575234D03*
X348000Y612661D03*
X352472Y581000D03*
X325762Y596900D03*
X324900Y581600D03*
X291839Y578193D03*
X293697Y589566D03*
X289070Y573080D03*
X355700Y579317D03*
X341755Y627231D03*
Y623682D03*
X341600Y616962D03*
Y613413D03*
X334264Y602648D03*
X337813D03*
X352716Y594135D03*
X350746Y574837D03*
X293500Y625600D03*
X293600Y629100D03*
X321421Y605265D03*
X323413Y602491D03*
X303000Y586800D03*
X292006Y574797D03*
X315616Y571817D03*
X289800Y569182D03*
X315893Y567721D03*
X341558Y567689D03*
X300043Y603619D03*
X303468Y603647D03*
X352716Y590535D03*
X347784Y587509D03*
X336923Y586749D03*
X347784Y584109D03*
X336923Y583349D03*
X307650Y596000D03*
X285400Y572556D03*
X325761Y592959D03*
X315315Y575204D03*
X317813Y580469D03*
X286400Y569200D03*
X317813Y584969D03*
X325899Y589186D03*
X297118Y668882D03*
X294804Y695204D03*
X292400Y640500D03*
X332824Y684270D03*
X348314Y643853D03*
X332800Y691970D03*
X318000Y678270D03*
X304100Y666500D03*
X351547Y645938D03*
X355100Y651827D03*
X314398Y670254D03*
X340000Y662200D03*
X353700Y670900D03*
X352800Y702960D03*
X328356Y678679D03*
X297900Y664800D03*
X290600Y668200D03*
X338301Y673907D03*
X328600Y661100D03*
X343372Y655836D03*
X347013Y656090D03*
X328087Y701587D03*
X327062Y697600D03*
X332200Y643800D03*
X288720Y641455D03*
X289473Y657061D03*
X336000Y662200D03*
X336387Y648987D03*
X317516Y671612D03*
X315000Y674900D03*
X338135Y670511D03*
X342542Y685983D03*
X342645Y682506D03*
X300700Y667000D03*
X330593Y671019D03*
X303741Y654095D03*
X329989Y653920D03*
X298570Y743670D03*
X306470Y743570D03*
X291700Y737000D03*
X316465Y716063D03*
X287220Y737920D03*
X334000Y714640D03*
X293075Y726600D03*
X342208Y714950D03*
X337481Y719818D03*
X380500Y33500D03*
Y30000D03*
X382631Y48200D03*
X382547Y52800D03*
X375300Y62150D03*
X384000Y30000D03*
X425765Y56265D03*
X372500Y44500D03*
Y56500D03*
X375300Y72050D03*
X357500Y104200D03*
X394070Y80840D03*
X385964Y80089D03*
X382500Y88000D03*
X376000Y78400D03*
X366500Y124700D03*
X363100Y124600D03*
X387833Y82930D03*
X391382D03*
X372500Y90000D03*
Y78000D03*
X396800Y74800D03*
X405100Y159300D03*
X400000Y159200D03*
X365900Y198500D03*
X365800Y193750D03*
X399900Y152100D03*
X400924Y155896D03*
X404473D03*
X398000Y165400D03*
X398050Y162000D03*
X406400Y150300D03*
X362150Y214174D03*
X364000Y240100D03*
X363828Y243944D03*
X381009Y343909D03*
X380799Y347303D03*
X386250Y318250D03*
X380600Y335700D03*
X373700Y329700D03*
X376910Y366078D03*
X359323Y372277D03*
X363699Y382608D03*
X363703Y386008D03*
X363586Y375809D03*
X363701Y379208D03*
X377300Y362700D03*
X379448Y487250D03*
X361250Y491650D03*
X363942Y450591D03*
X366700Y454800D03*
X359400Y451600D03*
X381276Y469106D03*
X374030Y449526D03*
X372575Y452600D03*
X380200Y457800D03*
X381400Y462000D03*
X370800Y475128D03*
X389081Y475224D03*
X387950Y466800D03*
X394700Y481700D03*
X394952Y485300D03*
X378937Y443491D03*
X376697Y446050D03*
X373576Y466300D03*
X373534Y462830D03*
X370900Y471700D03*
X373700Y482700D03*
X377691Y451891D03*
X381370Y465500D03*
X388123Y492432D03*
X378840Y448690D03*
X361013Y475128D03*
X368100Y513100D03*
X387800Y529400D03*
X367500Y526800D03*
X393100Y564400D03*
X362801Y548097D03*
X366900Y499942D03*
X372714Y509275D03*
X364000Y525500D03*
X387400Y547500D03*
X384400Y545195D03*
X362666Y504265D03*
X390651Y499000D03*
X387800Y525500D03*
X387700Y521600D03*
X376617Y544817D03*
X397650Y508250D03*
Y536671D03*
X362280Y554590D03*
X397650Y519400D03*
X394880Y548670D03*
X397650Y523900D03*
X393465Y553100D03*
X387700Y517700D03*
X362500Y499970D03*
X365730Y541050D03*
X368900Y505000D03*
X372494Y513020D03*
X383126Y565162D03*
X366490Y564360D03*
X370763Y547900D03*
X370800Y551300D03*
Y554700D03*
X383080Y554897D03*
X384347Y558647D03*
X382922Y561735D03*
X372900Y538700D03*
X396400Y545500D03*
X393889Y543207D03*
X396200Y597200D03*
X394800Y609700D03*
X358646Y596456D03*
X359000Y635600D03*
X360980Y582586D03*
X394300Y576600D03*
X372951Y576851D03*
X377714Y631280D03*
X368399Y567372D03*
X367133Y596067D03*
X382380Y612620D03*
X371180Y629236D03*
X386224Y580524D03*
X383411Y577024D03*
X362250Y570875D03*
X364300Y592900D03*
X361227Y630300D03*
X378400Y594800D03*
X365953Y570753D03*
X382600Y609000D03*
X375700Y580102D03*
X390600Y625500D03*
X366100Y590000D03*
X380572Y592095D03*
X396300Y587000D03*
X396400Y583500D03*
X388418Y650549D03*
X385700Y641300D03*
X374200Y645871D03*
X374252Y641029D03*
X386050Y701200D03*
X379100Y703300D03*
X363664Y688950D03*
X384466Y661650D03*
X378832Y659705D03*
X388338Y643600D03*
Y647149D03*
X392100Y683900D03*
X392000Y679800D03*
X390500Y665800D03*
Y669200D03*
X396306Y698732D03*
X361914Y680181D03*
X401000Y676500D03*
X371457Y667593D03*
X368060Y667743D03*
X392079Y703434D03*
X396400Y659800D03*
X390355Y690926D03*
X373060Y702960D03*
X398600Y662700D03*
X379450Y714400D03*
X383600Y711800D03*
X372100Y711700D03*
X478426Y20427D03*
X496394Y30000D03*
X482727Y41870D03*
X486535Y47449D03*
X482397Y52176D03*
X472800Y50000D03*
X469000Y50100D03*
X499721Y46102D03*
X499623Y49524D03*
X446788Y55180D03*
X458041Y47341D03*
X476100Y60500D03*
X478700Y62800D03*
X462372Y49179D03*
X486400Y38500D03*
X467016Y20430D03*
X450454Y38147D03*
X486527Y41939D03*
X447233Y48829D03*
X496355Y26000D03*
X496242Y22287D03*
X460300Y57600D03*
X432269Y19980D03*
X486700Y31100D03*
X462874Y95922D03*
X487500Y73400D03*
X485700Y70500D03*
X448000Y80404D03*
X444800Y82404D03*
X478590Y70310D03*
X482200Y70500D03*
X498500Y84200D03*
X471281Y105681D03*
X455766Y114535D03*
X473600Y108300D03*
X457000Y117800D03*
X480538Y112071D03*
X459500Y95500D03*
X441100Y110950D03*
X448996Y117666D03*
X463479Y99412D03*
X504900Y18200D03*
X508646Y18386D03*
X518890Y59730D03*
X515700Y50899D03*
X515785Y55552D03*
X505633Y46932D03*
X502300Y58200D03*
X528300Y58648D03*
X515500Y59000D03*
X513500Y62000D03*
X532500Y58600D03*
X513379Y103325D03*
X502379Y103194D03*
X543059Y108958D03*
X540800Y111500D03*
X501100Y86800D03*
X538456Y65144D03*
X509981Y103194D03*
X505779D03*
X513300Y83000D03*
X503700Y107600D03*
X599254Y37967D03*
X582447Y50607D03*
X588647Y28007D03*
X576649Y39585D03*
X575300Y45967D03*
X586754Y53967D03*
X577847Y50807D03*
X582797Y31807D03*
X600847Y33907D03*
X588753Y24080D03*
X603747Y71407D03*
X636647Y64300D03*
X642998Y127863D03*
X642574Y131843D03*
X710550Y18550D03*
X685907Y30622D03*
X673647Y33107D03*
X680300Y17500D03*
X680000Y23900D03*
X675903Y29541D03*
X668531Y71500D03*
X713200Y387700D03*
X700900Y423800D03*
X696070Y483486D03*
X712874Y470182D03*
X707391Y484208D03*
X712000Y442100D03*
X711300Y423800D03*
X701183Y453339D03*
X704836D03*
X709700Y480332D03*
X698651Y428165D03*
X669749Y458022D03*
X683000Y447200D03*
X680200Y449500D03*
X705450Y440950D03*
X705700Y493500D03*
X708367Y491000D03*
X715000Y547027D03*
X705853Y549017D03*
X708682Y551846D03*
X711156Y554320D03*
X713985Y557149D03*
X696624Y548249D03*
X699453Y551078D03*
X701927Y553552D03*
X704756Y556381D03*
X683369Y549269D03*
X686198Y552098D03*
X688672Y554572D03*
X691501Y557401D03*
X681989Y540183D03*
X684818Y543012D03*
X687292Y545486D03*
X690121Y548315D03*
X668195Y541742D03*
X671024Y544571D03*
X673498Y547045D03*
X676327Y549874D03*
X655092Y536171D03*
X657921Y539000D03*
X660395Y541474D03*
X663224Y544303D03*
X713189Y524511D03*
X707283D03*
X701378D03*
X695472D03*
X689567D03*
X683661D03*
X677756D03*
X662400Y519500D03*
X666800D03*
X657199Y530195D03*
X671850Y524511D03*
X653634Y513757D03*
X656846Y521702D03*
X678740Y508760D03*
X777500Y34500D03*
X766200Y22000D03*
X723800Y18600D03*
X725288Y405950D03*
X783800Y422800D03*
X718300Y387700D03*
X740500Y426800D03*
X716100Y442100D03*
X721100D03*
X725200D03*
X740500Y431000D03*
X723800Y475164D03*
X785434Y551934D03*
X788263Y554763D03*
X775934Y550934D03*
X778763Y553763D03*
X781237Y556237D03*
X784066Y559066D03*
X765434Y549934D03*
X768263Y552763D03*
X770737Y555237D03*
X773566Y558066D03*
X753434Y545434D03*
X756263Y548263D03*
X758737Y550737D03*
X761566Y553566D03*
X725853Y547117D03*
X728682Y549946D03*
X731156Y552420D03*
X733985Y555249D03*
X717829Y549856D03*
X720303Y552330D03*
X723132Y555159D03*
X716536Y523519D03*
X720536D03*
X724036D03*
X728036D03*
X762679Y535537D03*
X742716Y536435D03*
X738779D03*
X782086D03*
X776181D03*
X770275D03*
X725000D03*
X719394Y536305D03*
X759342Y543603D03*
X765935Y537009D03*
X777165Y509835D03*
X854596Y155288D03*
X840122Y156614D03*
X843160Y169467D03*
X845168Y192764D03*
X851137Y199864D03*
X858622Y155614D03*
X854634Y166390D03*
X842511Y164078D03*
X842022Y152174D03*
X858632Y216929D03*
X857700Y222300D03*
X848868Y219064D03*
X850730Y350483D03*
X841116Y348914D03*
X820059Y331701D03*
X835316Y340914D03*
X846456Y350814D03*
X808188Y404950D03*
X815541Y354089D03*
X847720Y371072D03*
X856720Y409372D03*
X809702Y416359D03*
X822300Y418900D03*
X831650Y422612D03*
X830531Y361589D03*
X794200Y422800D03*
X811300Y395900D03*
X801200Y386700D03*
X796100D03*
X821800Y400500D03*
X821700Y403900D03*
X842820Y382172D03*
X816997Y371022D03*
X847629Y391998D03*
X855320Y414472D03*
X830133Y353930D03*
X842916Y357214D03*
X849420Y407748D03*
X822300Y390000D03*
X804000Y441100D03*
X799000D03*
X811142Y470358D03*
X811668Y433703D03*
X820150Y433900D03*
X794900Y441100D03*
X808100D03*
X807400Y477229D03*
X823710Y469835D03*
X803300Y491600D03*
X806888Y491398D03*
X822434Y550434D03*
X825263Y553263D03*
X827737Y555737D03*
X830566Y558566D03*
X809934Y545434D03*
X812763Y548263D03*
X815237Y550737D03*
X818066Y553566D03*
X803934Y551934D03*
X806763Y554763D03*
X809237Y557237D03*
X812066Y560066D03*
X794934Y551434D03*
X797763Y554263D03*
X800237Y556737D03*
X803066Y559566D03*
X790737Y557237D03*
X793566Y560066D03*
X845198Y552063D03*
X842369Y549234D03*
X839895Y546760D03*
X837066Y543931D03*
X825000Y536200D03*
X817519Y536435D03*
X811614D03*
X805708D03*
X841141D03*
X837204D03*
X799803D03*
X793897D03*
X787992D03*
X867653Y172764D03*
X867851Y163585D03*
X864492Y206435D03*
X860868Y219764D03*
X868433Y349134D03*
X864920Y368972D03*
X861484Y399069D03*
X1105450Y838875D03*
G54D13*
X34652Y111485D03*
X33297Y703990D03*
X148206Y21054D03*
X261147Y405580D03*
X486498Y356293D03*
X807831Y734367D03*
X899219Y47960D03*
X1105450Y356925D03*
G54D31*
X488838Y164744D03*
X1105450Y328575D03*
G54D22*
X163189Y669291D03*
X1105450Y527025D03*
G54D14*
X70865Y98425D03*
Y472441D03*
X314960D03*
X364173Y740157D03*
X405511Y39370D03*
X587795Y307087D03*
X590551Y472441D03*
X612204Y606299D03*
X875984Y472441D03*
Y606299D03*
Y740157D03*
X1105450Y583725D03*
G54D23*
X346457Y57007D03*
X353543Y62913D03*
Y55039D03*
X346457Y66850D03*
Y74724D03*
Y84567D03*
X353543Y86535D03*
Y78661D03*
Y70787D03*
X1105450Y668775D03*
G54D32*
X706299Y83661D03*
Y201771D03*
X804724Y83661D03*
Y201772D03*
X1105450Y186825D03*
G54D15*
X60600Y670900D03*
X65900Y671000D03*
X65714Y665850D03*
X60800Y660900D03*
X60700Y665900D03*
X65700Y660900D03*
X139916Y709422D03*
X130019Y709695D03*
X139916Y705822D03*
X130019Y706095D03*
X135019D03*
X70700Y671000D03*
X70800Y660700D03*
X70600Y665800D03*
X139916Y713022D03*
Y716622D03*
Y720222D03*
Y723822D03*
X130019Y713295D03*
Y716895D03*
Y720495D03*
X135019Y710595D03*
Y723595D03*
Y719095D03*
Y714845D03*
X130019Y724095D03*
X265400Y446100D03*
X312289Y535181D03*
X311386Y633450D03*
X306300Y638600D03*
X301286Y638650D03*
X301386Y633650D03*
X306286D03*
X311186Y638550D03*
X300720Y704920D03*
X300520Y710020D03*
X290620Y710120D03*
X295634Y710070D03*
X290720Y705120D03*
X295620D03*
X301186Y643650D03*
X306486Y643750D03*
X311286D03*
X300620Y715220D03*
X290520Y715120D03*
X295820Y715220D03*
X365164Y612620D03*
X358864D03*
X371400Y606400D03*
X358800Y606300D03*
X365300Y606500D03*
X371400Y612700D03*
X371300Y618800D03*
X365500Y619000D03*
X358900Y618800D03*
X468000Y31500D03*
Y39500D03*
X464000Y35500D03*
X468000Y35400D03*
X472000Y35500D03*
X603943Y42806D03*
X608143Y42906D03*
X603943Y47006D03*
X608043D03*
X706275Y445986D03*
X753800Y535000D03*
X857020Y383172D03*
Y379572D03*
Y386772D03*
X875272Y186265D03*
X878872D03*
X860872D03*
X871672D03*
X868072D03*
X864472D03*
X878372Y191265D03*
X878872Y196265D03*
X864472D03*
X868072D03*
X871672D03*
X875272D03*
X865372Y191265D03*
X873872D03*
X869622D03*
X860872Y196265D03*
Y191265D03*
X871420Y383172D03*
X875020D03*
Y379572D03*
X871420D03*
X867820D03*
X860620D03*
X864220D03*
X875020Y386772D03*
X871420D03*
X867820D03*
X860620D03*
X864220D03*
X867820Y383172D03*
X860620D03*
X864220D03*
X1105450Y782175D03*
G54D24*
X339331Y49803D03*
X360669Y91929D03*
X1105450Y215175D03*
G54D33*
X666929Y510236D03*
X765354D03*
X1105450Y441975D03*
G54D25*
X339331Y91929D03*
X360669Y49803D03*
X1105450Y243525D03*
G54D34*
X745669Y510236D03*
X844094D03*
X1105450Y385275D03*
G54D16*
X49212Y740157D03*
X875984Y31496D03*
X1105450Y555375D03*
G54D35*
X801024Y24409D03*
X811024D03*
X821024D03*
X1105450Y640425D03*
G54D17*
X89764Y238386D03*
X309252Y413583D03*
X1105450Y158475D03*
G54D26*
X305906Y182874D03*
X1105450Y413625D03*
G54D36*
G01X-36569Y-23804D02*
Y-103804D01*
G01D02*
X1258031D01*
G01X-40569Y-7804D02*
G02I-12000J0D01*
G01X-45719D02*
G02I-6850J0D01*
G01X-52569Y-23804D02*
Y8196D01*
G01X-36569Y-23804D02*
X1258031D01*
G01X-36569Y-59304D02*
X1258031D01*
G01X-36569Y-7804D02*
X-68569D01*
G01X470531Y-23804D02*
Y-103804D01*
G01X608031Y-23804D02*
Y-103804D01*
G01X723031Y-23804D02*
Y-103804D01*
G01X890531Y-23804D02*
Y-103804D01*
G01X1060531Y-23804D02*
Y-103804D01*
G01X1258031Y-23804D02*
Y-103804D01*
G01X1286031Y-7804D02*
G02I-12000J0D01*
G01X1280881D02*
G02I-6850J0D01*
G01X1274031Y-23804D02*
Y8196D01*
G01X1290031Y-7804D02*
X1258031D01*
G54D27*
X305906Y388386D03*
X1105450Y470325D03*
G54D18*
X90157Y413582D03*
X309055Y157677D03*
X1105450Y271875D03*
G54D37*
G01X-9023Y-84471D02*
X-8149Y-83596D01*
X-7494Y-82138D01*
X-7057Y-80095D01*
X-7494Y-78346D01*
X-8367Y-77179D01*
X-9896Y-76304D01*
X-15791D01*
Y-93804D01*
X-8586D01*
X-7057Y-92638D01*
X-6184Y-90887D01*
X-5747Y-88846D01*
X-6184Y-86804D01*
X-7494Y-85054D01*
X-9023Y-84471D01*
X-15791D01*
G01X3674Y-93804D02*
Y-82138D01*
G01Y-84471D02*
X4766Y-83304D01*
X5858Y-82429D01*
X7386Y-82138D01*
X8477Y-82429D01*
X9788Y-83304D01*
G01X19646Y-99054D02*
X20956Y-99637D01*
X22703Y-99054D01*
X23794Y-97888D01*
X24668Y-96429D01*
X25977Y-91763D01*
X28816Y-82138D01*
G01X21829D02*
X25977Y-91763D01*
G01X45224Y-83596D02*
X43696Y-82429D01*
X42386Y-82138D01*
X40639Y-82721D01*
X39329Y-83887D01*
X38456Y-85929D01*
X38237Y-87971D01*
X38456Y-90013D01*
X39329Y-91763D01*
X40639Y-93221D01*
X42386Y-93804D01*
X43914Y-93221D01*
X45224Y-92054D01*
G01X55956Y-85929D02*
X62943D01*
X62288Y-83887D01*
X61196Y-82721D01*
X59668Y-82138D01*
X58139Y-82429D01*
X56829Y-83304D01*
X55956Y-85346D01*
X55519Y-87096D01*
Y-88846D01*
X55956Y-90596D01*
X57048Y-92346D01*
X58358Y-93512D01*
X59886Y-93804D01*
X61414Y-93221D01*
X62943Y-91471D01*
G01X99034Y-77763D02*
X97724Y-76887D01*
X96196Y-76304D01*
X94449D01*
X92484Y-77179D01*
X90956Y-78637D01*
X89864Y-80388D01*
X88991Y-83304D01*
X88772Y-85929D01*
X89209Y-88554D01*
X89864Y-90304D01*
X91174Y-92054D01*
X92703Y-93221D01*
X94231Y-93804D01*
X95759D01*
X97288Y-93221D01*
X98598Y-92346D01*
X99690Y-91180D01*
G01X115661Y-93804D02*
Y-82138D01*
G01Y-84179D02*
X114788Y-83013D01*
X113477Y-82429D01*
X111949Y-82138D01*
X110421Y-82721D01*
X109111Y-83887D01*
X108237Y-85637D01*
X107801Y-87971D01*
X108237Y-90304D01*
X109111Y-92054D01*
X110421Y-93221D01*
X111949Y-93804D01*
X113477Y-93512D01*
X114788Y-92638D01*
X115661Y-91471D01*
G01X125519Y-93804D02*
Y-82138D01*
G01Y-85054D02*
X126393Y-83596D01*
X127703Y-82429D01*
X129449Y-82138D01*
X130977Y-82429D01*
X132288Y-83596D01*
X132943Y-85637D01*
Y-93804D01*
G01X142146Y-99054D02*
X143456Y-99637D01*
X145203Y-99054D01*
X146294Y-97888D01*
X147168Y-96429D01*
X148477Y-91763D01*
X151316Y-82138D01*
G01X144329D02*
X148477Y-91763D01*
G01X164231Y-93804D02*
X162921Y-93512D01*
X161611Y-92346D01*
X160737Y-90304D01*
X160301Y-87971D01*
X160737Y-85637D01*
X161611Y-83596D01*
X162921Y-82429D01*
X164231Y-82138D01*
X165541Y-82429D01*
X166851Y-83596D01*
X167724Y-85637D01*
X167943Y-87971D01*
X167724Y-90304D01*
X166851Y-92346D01*
X165541Y-93512D01*
X164231Y-93804D01*
G01X178019D02*
Y-82138D01*
G01Y-85054D02*
X178893Y-83596D01*
X180203Y-82429D01*
X181949Y-82138D01*
X183477Y-82429D01*
X184788Y-83596D01*
X185443Y-85637D01*
Y-93804D01*
G01X214111Y-76304D02*
X219351D01*
G01X216731D02*
Y-93804D01*
G01X214111D02*
X219351D01*
G01X234231D02*
X232484Y-93512D01*
X230956Y-92346D01*
X229646Y-90596D01*
X228772Y-88554D01*
X228336Y-86221D01*
Y-83887D01*
X228772Y-81554D01*
X229646Y-79512D01*
X230956Y-77763D01*
X232484Y-76596D01*
X234231Y-76304D01*
X235977Y-76596D01*
X237506Y-77763D01*
X238816Y-79512D01*
X239690Y-81554D01*
X240126Y-83887D01*
Y-86221D01*
X239690Y-88554D01*
X238816Y-90596D01*
X237506Y-92346D01*
X235977Y-93512D01*
X234231Y-93804D01*
G01X246054D02*
Y-76304D01*
X251731Y-90887D01*
X257408Y-76304D01*
Y-93804D01*
G01X285639Y-99637D02*
X283456Y-96721D01*
X282364Y-93804D01*
Y-82138D01*
X283456Y-79221D01*
X285639Y-76304D01*
G01X298554Y-93804D02*
Y-76304D01*
X304231Y-90887D01*
X309908Y-76304D01*
Y-93804D01*
G01X321731Y-94387D02*
X321294Y-94096D01*
Y-93512D01*
X321731Y-93221D01*
X322168Y-93512D01*
Y-94096D01*
X321731Y-94387D01*
G01X335083Y-79221D02*
X336393Y-77471D01*
X337921Y-76596D01*
X339668Y-76304D01*
X341851Y-76887D01*
X343379Y-78346D01*
X343816Y-80095D01*
X343598Y-81846D01*
X342724Y-83304D01*
X338358Y-86221D01*
X336393Y-88262D01*
X335083Y-91180D01*
X334646Y-93804D01*
X343816D01*
G01X374231D02*
X372921Y-93512D01*
X371611Y-92346D01*
X370737Y-90304D01*
X370301Y-87971D01*
X370737Y-85637D01*
X371611Y-83596D01*
X372921Y-82429D01*
X374231Y-82138D01*
X375541Y-82429D01*
X376851Y-83596D01*
X377724Y-85637D01*
X377943Y-87971D01*
X377724Y-90304D01*
X376851Y-92346D01*
X375541Y-93512D01*
X374231Y-93804D01*
G01X388019D02*
Y-82138D01*
G01Y-85054D02*
X388893Y-83596D01*
X390203Y-82429D01*
X391949Y-82138D01*
X393477Y-82429D01*
X394788Y-83596D01*
X395443Y-85637D01*
Y-93804D01*
G01X409231D02*
Y-76304D01*
G01X422146Y-99054D02*
X423456Y-99637D01*
X425203Y-99054D01*
X426294Y-97888D01*
X427168Y-96429D01*
X428477Y-91763D01*
X431316Y-82138D01*
G01X424329D02*
X428477Y-91763D01*
G01X445323Y-99637D02*
X447506Y-96721D01*
X448598Y-93804D01*
Y-82138D01*
X447506Y-79221D01*
X445323Y-76304D01*
G01X89631Y245086D02*
X89614Y251086D01*
G01X88117Y250082D02*
X89631Y245086D01*
X91117Y250090D01*
X88117Y250082D01*
G01X96464Y231686D02*
X83064D01*
G02Y245086I0J6700D01*
G01X96464D01*
G02Y231686I0J-6700D01*
G01X176054Y-48804D02*
Y-31304D01*
X181731Y-45887D01*
X187408Y-31304D01*
Y-48804D01*
G01X199231D02*
X197921Y-48512D01*
X196611Y-47346D01*
X195737Y-45304D01*
X195301Y-42971D01*
X195737Y-40637D01*
X196611Y-38596D01*
X197921Y-37429D01*
X199231Y-37138D01*
X200541Y-37429D01*
X201851Y-38596D01*
X202724Y-40637D01*
X202943Y-42971D01*
X202724Y-45304D01*
X201851Y-47346D01*
X200541Y-48512D01*
X199231Y-48804D01*
G01X220661Y-31304D02*
Y-48804D01*
G01Y-46180D02*
X219788Y-47638D01*
X218477Y-48512D01*
X216949Y-48804D01*
X215203Y-48221D01*
X213893Y-46763D01*
X213019Y-45013D01*
X212801Y-42971D01*
X213019Y-40929D01*
X213893Y-39179D01*
X215203Y-37721D01*
X216949Y-37138D01*
X218477Y-37429D01*
X219569Y-38013D01*
X220661Y-39179D01*
G01X230956Y-40929D02*
X237943D01*
X237288Y-38887D01*
X236196Y-37721D01*
X234668Y-37138D01*
X233139Y-37429D01*
X231829Y-38304D01*
X230956Y-40346D01*
X230519Y-42096D01*
Y-43846D01*
X230956Y-45596D01*
X232048Y-47346D01*
X233358Y-48512D01*
X234886Y-48804D01*
X236414Y-48221D01*
X237943Y-46471D01*
G01X251731Y-48804D02*
Y-31304D01*
G01X339087Y53961D02*
X331693Y66135D01*
G01X335209Y57456D02*
X339087Y53961D01*
X337773Y59013D01*
X335209Y57456D01*
G01X337731Y47253D02*
Y52353D01*
G02X340931I1600J0D01*
G01Y47253D01*
G02X337731I-1600J0D01*
G01X338990Y89207D02*
X332106Y76109D01*
G01X337992Y84083D02*
X338990Y89207D01*
X335336Y85479D01*
X337992Y84083D01*
G01X337731Y90729D02*
Y93129D01*
G02X340931I1600J0D01*
G01Y90729D01*
G02X337731I-1600J0D01*
G01X309119Y420283D02*
X309102Y426283D01*
G01X307605Y425279D02*
X309119Y420283D01*
X310605Y425287D01*
X307605Y425279D01*
G01X315952Y406883D02*
X302552D01*
G02Y420283I0J6700D01*
G01X315952D01*
G02Y406883I0J-6700D01*
G01X360758Y52599D02*
X366749Y65506D01*
G01X361503Y57766D02*
X360758Y52599D01*
X364224Y56503D01*
X361503Y57766D01*
G01X359069Y48603D02*
Y51003D01*
G02X362269I1600J0D01*
G01Y48603D01*
G02X359069I-1600J0D01*
G01X361363Y87973D02*
X366239Y76500D01*
G01X364699Y83958D02*
X361363Y87973D01*
X361938Y82785D01*
X364699Y83958D01*
G01X359069Y89379D02*
Y94479D01*
G02X362269I1600J0D01*
G01Y89379D01*
G02X359069I-1600J0D01*
G01X504231Y-93804D02*
Y-76304D01*
X501611Y-79804D01*
G01Y-93804D02*
X506851D01*
G01X517583Y-86513D02*
X519111Y-84471D01*
X520421Y-83304D01*
X522168Y-82721D01*
X523696Y-83304D01*
X524788Y-84471D01*
X525661Y-86221D01*
X525879Y-88262D01*
X525661Y-90013D01*
X524788Y-91763D01*
X523477Y-93221D01*
X521949Y-93804D01*
X520203Y-93221D01*
X518674Y-91471D01*
X517801Y-88846D01*
X517583Y-85929D01*
X518019Y-82138D01*
X518674Y-80095D01*
X519766Y-78054D01*
X521294Y-76596D01*
X522823Y-76304D01*
X524351Y-76887D01*
X525443Y-78346D01*
G01X534428Y-90304D02*
X535737Y-92346D01*
X537484Y-93512D01*
X539449Y-93804D01*
X541196Y-93512D01*
X542943Y-92054D01*
X544034Y-90304D01*
X544253Y-88554D01*
X543816Y-86513D01*
X542288Y-85054D01*
X540759Y-84471D01*
X538794D01*
G01X540759D02*
X542069Y-83596D01*
X543161Y-82138D01*
X543598Y-80388D01*
X543161Y-78637D01*
X542069Y-77179D01*
X540104Y-76304D01*
X538139Y-76596D01*
X536174Y-77763D01*
G01X559351Y-93804D02*
Y-76304D01*
X551272Y-88846D01*
X562190D01*
G01X570083Y-79221D02*
X571393Y-77471D01*
X572921Y-76596D01*
X574668Y-76304D01*
X576851Y-76887D01*
X578379Y-78346D01*
X578816Y-80095D01*
X578598Y-81846D01*
X577724Y-83304D01*
X573358Y-86221D01*
X571393Y-88262D01*
X570083Y-91180D01*
X569646Y-93804D01*
X578816D01*
G01X491114Y-48804D02*
Y-31304D01*
X496354D01*
X498101Y-32179D01*
X499411Y-34221D01*
X499848Y-36554D01*
X499411Y-38887D01*
X498319Y-40637D01*
X496354Y-41513D01*
X491114D01*
G01X517784Y-32763D02*
X516474Y-31887D01*
X514946Y-31304D01*
X513199D01*
X511234Y-32179D01*
X509706Y-33637D01*
X508614Y-35388D01*
X507741Y-38304D01*
X507522Y-40929D01*
X507959Y-43554D01*
X508614Y-45304D01*
X509924Y-47054D01*
X511453Y-48221D01*
X512981Y-48804D01*
X514509D01*
X516038Y-48221D01*
X517348Y-47346D01*
X518440Y-46180D01*
G01X532227Y-39471D02*
X533101Y-38596D01*
X533756Y-37138D01*
X534193Y-35095D01*
X533756Y-33346D01*
X532883Y-32179D01*
X531354Y-31304D01*
X525459D01*
Y-48804D01*
X532664D01*
X534193Y-47638D01*
X535066Y-45887D01*
X535503Y-43846D01*
X535066Y-41804D01*
X533756Y-40054D01*
X532227Y-39471D01*
X525459D01*
G01X541431Y-54637D02*
X554531D01*
G01X560459Y-48804D02*
Y-31304D01*
X570503Y-48804D01*
Y-31304D01*
G01X582981Y-48804D02*
X581234Y-48512D01*
X579706Y-47346D01*
X578396Y-45596D01*
X577522Y-43554D01*
X577086Y-41221D01*
Y-38887D01*
X577522Y-36554D01*
X578396Y-34512D01*
X579706Y-32763D01*
X581234Y-31596D01*
X582981Y-31304D01*
X584727Y-31596D01*
X586256Y-32763D01*
X587566Y-34512D01*
X588440Y-36554D01*
X588876Y-38887D01*
Y-41221D01*
X588440Y-43554D01*
X587566Y-45596D01*
X586256Y-47346D01*
X584727Y-48512D01*
X582981Y-48804D01*
G01X633822Y-31304D02*
X639281Y-48804D01*
X644740Y-31304D01*
G01X661148Y-48804D02*
X652414D01*
Y-31304D01*
X661148D01*
G01X657654Y-39762D02*
X652414D01*
G01X669914Y-48804D02*
Y-31304D01*
X675373D01*
X677119Y-32179D01*
X678211Y-33346D01*
X678648Y-35679D01*
X678211Y-38013D01*
X676901Y-39471D01*
X675373Y-40346D01*
X669914D01*
G01X675373D02*
X678648Y-48804D01*
G01X691781Y-49387D02*
X691344Y-49096D01*
Y-48512D01*
X691781Y-48221D01*
X692218Y-48512D01*
Y-49096D01*
X691781Y-49387D01*
G01X661383Y-79221D02*
X662693Y-77471D01*
X664221Y-76596D01*
X665968Y-76304D01*
X668151Y-76887D01*
X669679Y-78346D01*
X670116Y-80095D01*
X669898Y-81846D01*
X669024Y-83304D01*
X664658Y-86221D01*
X662693Y-88262D01*
X661383Y-91180D01*
X660946Y-93804D01*
X670116D01*
G01X712649Y83611D02*
X718349Y83561D01*
G01X717662Y85067D02*
X712649Y83611D01*
X717636Y82067D01*
X717662Y85067D01*
G01X712599Y80511D02*
Y86811D01*
G03X699999I-6300J0D01*
G01Y80511D01*
G03X712599I6300J0D01*
G01X712649Y201721D02*
X718349Y201671D01*
G01X717662Y203177D02*
X712649Y201721D01*
X717636Y200177D01*
X717662Y203177D01*
G01X712599Y198621D02*
Y204921D01*
G03X699999I-6300J0D01*
G01Y198621D01*
G03X712599I6300J0D01*
G01X766928Y-93804D02*
Y-76304D01*
X771294D01*
X773041Y-77179D01*
X774351Y-78346D01*
X775443Y-80095D01*
X776316Y-82138D01*
X776534Y-85054D01*
X776316Y-87971D01*
X775443Y-90013D01*
X774351Y-91763D01*
X773041Y-92929D01*
X771294Y-93804D01*
X766928D01*
G01X784864D02*
Y-76304D01*
X790323D01*
X792069Y-77179D01*
X793161Y-78346D01*
X793598Y-80679D01*
X793161Y-83013D01*
X791851Y-84471D01*
X790323Y-85346D01*
X784864D01*
G01X790323D02*
X793598Y-93804D01*
G01X804111Y-76304D02*
X809351D01*
G01X806731D02*
Y-93804D01*
G01X804111D02*
X809351D01*
G01X819864Y-76304D02*
Y-93804D01*
X828598D01*
G01X837364Y-76304D02*
Y-93804D01*
X846098D01*
G01X767364Y-31304D02*
Y-48804D01*
X776098D01*
G01X793161D02*
Y-37138D01*
G01Y-39179D02*
X792288Y-38013D01*
X790977Y-37429D01*
X789449Y-37138D01*
X787921Y-37721D01*
X786611Y-38887D01*
X785737Y-40637D01*
X785301Y-42971D01*
X785737Y-45304D01*
X786611Y-47054D01*
X787921Y-48221D01*
X789449Y-48804D01*
X790977Y-48512D01*
X792288Y-47638D01*
X793161Y-46471D01*
G01X802146Y-54054D02*
X803456Y-54637D01*
X805203Y-54054D01*
X806294Y-52888D01*
X807168Y-51429D01*
X808477Y-46763D01*
X811316Y-37138D01*
G01X804329D02*
X808477Y-46763D01*
G01X820956Y-40929D02*
X827943D01*
X827288Y-38887D01*
X826196Y-37721D01*
X824668Y-37138D01*
X823139Y-37429D01*
X821829Y-38304D01*
X820956Y-40346D01*
X820519Y-42096D01*
Y-43846D01*
X820956Y-45596D01*
X822048Y-47346D01*
X823358Y-48512D01*
X824886Y-48804D01*
X826414Y-48221D01*
X827943Y-46471D01*
G01X838674Y-48804D02*
Y-37138D01*
G01Y-39471D02*
X839766Y-38304D01*
X840858Y-37429D01*
X842386Y-37138D01*
X843477Y-37429D01*
X844788Y-38304D01*
G01X811074Y83611D02*
X816774Y83561D01*
G01X816087Y85067D02*
X811074Y83611D01*
X816061Y82067D01*
X816087Y85067D01*
G01X811024Y80511D02*
Y86811D01*
G03X798424I-6300J0D01*
G01Y80511D01*
G03X811024I6300J0D01*
G01X811074Y201722D02*
X816774Y201672D01*
G01X816087Y203178D02*
X811074Y201722D01*
X816061Y200178D01*
X816087Y203178D01*
G01X811024Y198622D02*
Y204922D01*
G03X798424I-6300J0D01*
G01Y198622D01*
G03X811024I6300J0D01*
G01X931781Y-93804D02*
X930034Y-93512D01*
X928506Y-92346D01*
X927196Y-90596D01*
X926322Y-88554D01*
X925886Y-86221D01*
Y-83887D01*
X926322Y-81554D01*
X927196Y-79512D01*
X928506Y-77763D01*
X930034Y-76596D01*
X931781Y-76304D01*
X933527Y-76596D01*
X935056Y-77763D01*
X936366Y-79512D01*
X937240Y-81554D01*
X937676Y-83887D01*
Y-86221D01*
X937240Y-88554D01*
X936366Y-90596D01*
X935056Y-92346D01*
X933527Y-93512D01*
X931781Y-93804D01*
G01X933527Y-89137D02*
X936148Y-93804D01*
G01X944478Y-76304D02*
Y-88846D01*
X945351Y-91471D01*
X947098Y-93221D01*
X949281Y-93804D01*
X951464Y-93221D01*
X953211Y-91471D01*
X954084Y-88846D01*
Y-76304D01*
G01X964161D02*
X969401D01*
G01X966781D02*
Y-93804D01*
G01X964161D02*
X969401D01*
G01X979259D02*
Y-76304D01*
X989303Y-93804D01*
Y-76304D01*
G01X1006584Y-77763D02*
X1005274Y-76887D01*
X1003746Y-76304D01*
X1001999D01*
X1000034Y-77179D01*
X998506Y-78637D01*
X997414Y-80388D01*
X996541Y-83304D01*
X996322Y-85929D01*
X996759Y-88554D01*
X997414Y-90304D01*
X998724Y-92054D01*
X1000253Y-93221D01*
X1001781Y-93804D01*
X1003309D01*
X1004838Y-93221D01*
X1006148Y-92346D01*
X1007240Y-91180D01*
G01X1019281Y-93804D02*
Y-85929D01*
X1014914Y-76304D01*
G01X1023648D02*
X1019281Y-85929D01*
G01X909478Y-48804D02*
Y-31304D01*
X913844D01*
X915591Y-32179D01*
X916901Y-33346D01*
X917993Y-35095D01*
X918866Y-37138D01*
X919084Y-40054D01*
X918866Y-42971D01*
X917993Y-45013D01*
X916901Y-46763D01*
X915591Y-47929D01*
X913844Y-48804D01*
X909478D01*
G01X928506Y-40929D02*
X935493D01*
X934838Y-38887D01*
X933746Y-37721D01*
X932218Y-37138D01*
X930689Y-37429D01*
X929379Y-38304D01*
X928506Y-40346D01*
X928069Y-42096D01*
Y-43846D01*
X928506Y-45596D01*
X929598Y-47346D01*
X930908Y-48512D01*
X932436Y-48804D01*
X933964Y-48221D01*
X935493Y-46471D01*
G01X946006Y-46763D02*
X947098Y-47929D01*
X948626Y-48804D01*
X949936D01*
X951246Y-48221D01*
X952119Y-47346D01*
X952556Y-46180D01*
X952338Y-44429D01*
X951464Y-43554D01*
X947534Y-41804D01*
X946661Y-39762D01*
X947098Y-38304D01*
X947971Y-37429D01*
X949281Y-37138D01*
X950591Y-37429D01*
X951901Y-38304D01*
G01X966781Y-37138D02*
Y-48804D01*
G01Y-32471D02*
X966344Y-32179D01*
Y-31596D01*
X966781Y-31304D01*
X967218Y-31596D01*
Y-32179D01*
X966781Y-32471D01*
G01X981224Y-53179D02*
X982753Y-54346D01*
X984499Y-54637D01*
X986027Y-54346D01*
X987338Y-52888D01*
X988211Y-50846D01*
Y-37138D01*
G01Y-39471D02*
X987338Y-38304D01*
X986027Y-37429D01*
X984499Y-37138D01*
X982753Y-37721D01*
X981661Y-38887D01*
X980787Y-40929D01*
X980351Y-42971D01*
X980569Y-44721D01*
X981443Y-46763D01*
X982753Y-48221D01*
X984499Y-48804D01*
X985809Y-48512D01*
X987338Y-47346D01*
X988211Y-46180D01*
G01X998069Y-48804D02*
Y-37138D01*
G01Y-40054D02*
X998943Y-38596D01*
X1000253Y-37429D01*
X1001999Y-37138D01*
X1003527Y-37429D01*
X1004838Y-38596D01*
X1005493Y-40637D01*
Y-48804D01*
G01X1016006Y-40929D02*
X1022993D01*
X1022338Y-38887D01*
X1021246Y-37721D01*
X1019718Y-37138D01*
X1018189Y-37429D01*
X1016879Y-38304D01*
X1016006Y-40346D01*
X1015569Y-42096D01*
Y-43846D01*
X1016006Y-45596D01*
X1017098Y-47346D01*
X1018408Y-48512D01*
X1019936Y-48804D01*
X1021464Y-48221D01*
X1022993Y-46471D01*
G01X1033724Y-48804D02*
Y-37138D01*
G01Y-39471D02*
X1034816Y-38304D01*
X1035908Y-37429D01*
X1037436Y-37138D01*
X1038527Y-37429D01*
X1039838Y-38304D01*
G01X1061585Y114300D02*
Y126800D01*
X1068715Y114300D01*
Y126800D01*
G01X1077550Y114300D02*
X1076620Y114508D01*
X1075690Y115341D01*
X1075070Y116800D01*
X1074760Y118467D01*
X1075070Y120133D01*
X1075690Y121592D01*
X1076620Y122425D01*
X1077550Y122633D01*
X1078480Y122425D01*
X1079410Y121592D01*
X1080030Y120133D01*
X1080185Y118467D01*
X1080030Y116800D01*
X1079410Y115341D01*
X1078480Y114508D01*
X1077550Y114300D01*
G01X1089950Y126800D02*
Y114300D01*
G01X1087780Y122633D02*
X1092120D01*
G01X1100025Y119925D02*
X1104985D01*
X1104520Y121383D01*
X1103745Y122217D01*
X1102660Y122633D01*
X1101575Y122425D01*
X1100645Y121800D01*
X1100025Y120342D01*
X1099715Y119091D01*
Y117842D01*
X1100025Y116592D01*
X1100800Y115341D01*
X1101730Y114508D01*
X1102815Y114300D01*
X1103900Y114717D01*
X1104985Y115966D01*
G01X1114750Y113883D02*
X1114440Y114092D01*
Y114508D01*
X1114750Y114717D01*
X1115060Y114508D01*
Y114092D01*
X1114750Y113883D01*
G01Y119508D02*
X1114440Y119717D01*
Y120133D01*
X1114750Y120342D01*
X1115060Y120133D01*
Y119717D01*
X1114750Y119508D01*
G01X1124050Y114300D02*
Y126800D01*
X1127925D01*
X1129165Y126175D01*
X1129940Y125342D01*
X1130250Y123675D01*
X1129940Y122008D01*
X1129010Y120967D01*
X1127925Y120342D01*
X1124050D01*
G01X1127925D02*
X1130250Y114300D01*
G01X1137225Y119925D02*
X1142185D01*
X1141720Y121383D01*
X1140945Y122217D01*
X1139860Y122633D01*
X1138775Y122425D01*
X1137845Y121800D01*
X1137225Y120342D01*
X1136915Y119091D01*
Y117842D01*
X1137225Y116592D01*
X1138000Y115341D01*
X1138930Y114508D01*
X1140015Y114300D01*
X1141100Y114717D01*
X1142185Y115966D01*
G01X1151020Y114300D02*
Y124925D01*
X1151330Y125966D01*
X1151950Y126592D01*
X1152880Y126800D01*
X1153810Y126383D01*
X1154275Y125342D01*
G01X1152415Y121800D02*
X1149315D01*
G01X1162025Y119925D02*
X1166985D01*
X1166520Y121383D01*
X1165745Y122217D01*
X1164660Y122633D01*
X1163575Y122425D01*
X1162645Y121800D01*
X1162025Y120342D01*
X1161715Y119091D01*
Y117842D01*
X1162025Y116592D01*
X1162800Y115341D01*
X1163730Y114508D01*
X1164815Y114300D01*
X1165900Y114717D01*
X1166985Y115966D01*
G01X1174580Y114300D02*
Y122633D01*
G01Y120967D02*
X1175355Y121800D01*
X1176130Y122425D01*
X1177215Y122633D01*
X1177990Y122425D01*
X1178920Y121800D01*
G01X1201550Y126800D02*
Y114300D01*
G01X1199380Y122633D02*
X1203720D01*
G01X1213950Y114300D02*
X1213020Y114508D01*
X1212090Y115341D01*
X1211470Y116800D01*
X1211160Y118467D01*
X1211470Y120133D01*
X1212090Y121592D01*
X1213020Y122425D01*
X1213950Y122633D01*
X1214880Y122425D01*
X1215810Y121592D01*
X1216430Y120133D01*
X1216585Y118467D01*
X1216430Y116800D01*
X1215810Y115341D01*
X1214880Y114508D01*
X1213950Y114300D01*
G01X1235340D02*
Y126800D01*
X1238440D01*
X1239680Y126175D01*
X1240610Y125342D01*
X1241385Y124092D01*
X1242005Y122633D01*
X1242160Y120550D01*
X1242005Y118467D01*
X1241385Y117008D01*
X1240610Y115758D01*
X1239680Y114925D01*
X1238440Y114300D01*
X1235340D01*
G01X1248050D02*
Y126800D01*
X1251925D01*
X1253165Y126175D01*
X1253940Y125342D01*
X1254250Y123675D01*
X1253940Y122008D01*
X1253010Y120967D01*
X1251925Y120342D01*
X1248050D01*
G01X1251925D02*
X1254250Y114300D01*
G01X1261690Y126800D02*
X1265410D01*
G01X1263550D02*
Y114300D01*
G01X1261690D02*
X1265410D01*
G01X1272850Y126800D02*
Y114300D01*
X1279050D01*
G01X1285250Y126800D02*
Y114300D01*
X1291450D01*
G01X1313150D02*
Y126800D01*
G01X1328340Y114300D02*
Y122633D01*
G01Y121175D02*
X1327720Y122008D01*
X1326790Y122425D01*
X1325705Y122633D01*
X1324620Y122217D01*
X1323690Y121383D01*
X1323070Y120133D01*
X1322760Y118467D01*
X1323070Y116800D01*
X1323690Y115550D01*
X1324620Y114717D01*
X1325705Y114300D01*
X1326790Y114508D01*
X1327720Y115133D01*
X1328340Y115966D01*
G01X1334695Y110550D02*
X1335625Y110133D01*
X1336865Y110550D01*
X1337640Y111383D01*
X1338260Y112425D01*
X1339190Y115758D01*
X1341205Y122633D01*
G01X1336245D02*
X1339190Y115758D01*
G01X1348025Y119925D02*
X1352985D01*
X1352520Y121383D01*
X1351745Y122217D01*
X1350660Y122633D01*
X1349575Y122425D01*
X1348645Y121800D01*
X1348025Y120342D01*
X1347715Y119091D01*
Y117842D01*
X1348025Y116592D01*
X1348800Y115341D01*
X1349730Y114508D01*
X1350815Y114300D01*
X1351900Y114717D01*
X1352985Y115966D01*
G01X1360580Y114300D02*
Y122633D01*
G01Y120967D02*
X1361355Y121800D01*
X1362130Y122425D01*
X1363215Y122633D01*
X1363990Y122425D01*
X1364920Y121800D01*
G01X1386620Y114300D02*
Y124925D01*
X1386930Y125966D01*
X1387550Y126592D01*
X1388480Y126800D01*
X1389410Y126383D01*
X1389875Y125342D01*
G01X1388015Y121800D02*
X1384915D01*
G01X1399950Y114300D02*
X1399020Y114508D01*
X1398090Y115341D01*
X1397470Y116800D01*
X1397160Y118467D01*
X1397470Y120133D01*
X1398090Y121592D01*
X1399020Y122425D01*
X1399950Y122633D01*
X1400880Y122425D01*
X1401810Y121592D01*
X1402430Y120133D01*
X1402585Y118467D01*
X1402430Y116800D01*
X1401810Y115341D01*
X1400880Y114508D01*
X1399950Y114300D01*
G01X1410180D02*
Y122633D01*
G01Y120967D02*
X1410955Y121800D01*
X1411730Y122425D01*
X1412815Y122633D01*
X1413590Y122425D01*
X1414520Y121800D01*
G01X1440250Y114300D02*
X1434050D01*
Y126800D01*
X1440250D01*
G01X1437770Y120758D02*
X1434050D01*
G01X1446450Y126800D02*
Y114300D01*
X1452650D01*
G01X1458850Y126800D02*
Y114300D01*
X1465050D01*
G01X1472490Y126800D02*
X1476210D01*
G01X1474350D02*
Y114300D01*
G01X1472490D02*
X1476210D01*
G01X1483650D02*
Y126800D01*
X1487370D01*
X1488610Y126175D01*
X1489540Y124717D01*
X1489850Y123050D01*
X1489540Y121383D01*
X1488765Y120133D01*
X1487370Y119508D01*
X1483650D01*
G01X1495895Y115966D02*
X1497135Y114925D01*
X1498530Y114300D01*
X1499770D01*
X1501010Y114925D01*
X1501940Y115966D01*
X1502405Y117425D01*
X1502095Y118883D01*
X1501320Y120133D01*
X1499925Y120967D01*
X1498065Y121383D01*
X1496980Y122217D01*
X1496515Y123675D01*
X1496825Y125133D01*
X1497600Y126175D01*
X1498685Y126800D01*
X1499770D01*
X1500855Y126383D01*
X1501785Y125342D01*
G01X1514650Y114300D02*
X1508450D01*
Y126800D01*
X1514650D01*
G01X1512170Y120758D02*
X1508450D01*
G01X1539140Y126800D02*
Y114300D01*
G01Y116175D02*
X1538520Y115133D01*
X1537590Y114508D01*
X1536505Y114300D01*
X1535265Y114717D01*
X1534335Y115758D01*
X1533715Y117008D01*
X1533560Y118467D01*
X1533715Y119925D01*
X1534335Y121175D01*
X1535265Y122217D01*
X1536505Y122633D01*
X1537590Y122425D01*
X1538365Y122008D01*
X1539140Y121175D01*
G01X1546580Y114300D02*
Y122633D01*
G01Y120967D02*
X1547355Y121800D01*
X1548130Y122425D01*
X1549215Y122633D01*
X1549990Y122425D01*
X1550920Y121800D01*
G01X1561150Y122633D02*
Y114300D01*
G01Y125966D02*
X1560840Y126175D01*
Y126592D01*
X1561150Y126800D01*
X1561460Y126592D01*
Y126175D01*
X1561150Y125966D01*
G01X1573550Y114300D02*
Y126800D01*
G01X1585950Y114300D02*
Y126800D01*
G01X1613540D02*
Y114300D01*
G01Y116175D02*
X1612920Y115133D01*
X1611990Y114508D01*
X1610905Y114300D01*
X1609665Y114717D01*
X1608735Y115758D01*
X1608115Y117008D01*
X1607960Y118467D01*
X1608115Y119925D01*
X1608735Y121175D01*
X1609665Y122217D01*
X1610905Y122633D01*
X1611990Y122425D01*
X1612765Y122008D01*
X1613540Y121175D01*
G01X1623150Y122633D02*
Y114300D01*
G01Y125966D02*
X1622840Y126175D01*
Y126592D01*
X1623150Y126800D01*
X1623460Y126592D01*
Y126175D01*
X1623150Y125966D01*
G01X1633380Y114300D02*
Y122633D01*
G01Y120967D02*
X1634155Y121800D01*
X1634930Y122425D01*
X1636015Y122633D01*
X1636790Y122425D01*
X1637720Y121800D01*
G01X1645625Y119925D02*
X1650585D01*
X1650120Y121383D01*
X1649345Y122217D01*
X1648260Y122633D01*
X1647175Y122425D01*
X1646245Y121800D01*
X1645625Y120342D01*
X1645315Y119091D01*
Y117842D01*
X1645625Y116592D01*
X1646400Y115341D01*
X1647330Y114508D01*
X1648415Y114300D01*
X1649500Y114717D01*
X1650585Y115966D01*
G01X1662830Y121592D02*
X1661745Y122425D01*
X1660815Y122633D01*
X1659575Y122217D01*
X1658645Y121383D01*
X1658025Y119925D01*
X1657870Y118467D01*
X1658025Y117008D01*
X1658645Y115758D01*
X1659575Y114717D01*
X1660815Y114300D01*
X1661900Y114717D01*
X1662830Y115550D01*
G01X1672750Y126800D02*
Y114300D01*
G01X1670580Y122633D02*
X1674920D01*
G01X1685150D02*
Y114300D01*
G01Y125966D02*
X1684840Y126175D01*
Y126592D01*
X1685150Y126800D01*
X1685460Y126592D01*
Y126175D01*
X1685150Y125966D01*
G01X1697550Y114300D02*
X1696620Y114508D01*
X1695690Y115341D01*
X1695070Y116800D01*
X1694760Y118467D01*
X1695070Y120133D01*
X1695690Y121592D01*
X1696620Y122425D01*
X1697550Y122633D01*
X1698480Y122425D01*
X1699410Y121592D01*
X1700030Y120133D01*
X1700185Y118467D01*
X1700030Y116800D01*
X1699410Y115341D01*
X1698480Y114508D01*
X1697550Y114300D01*
G01X1707315D02*
Y122633D01*
G01Y120550D02*
X1707935Y121592D01*
X1708865Y122425D01*
X1710105Y122633D01*
X1711190Y122425D01*
X1712120Y121592D01*
X1712585Y120133D01*
Y114300D01*
G01X1060500Y144300D02*
Y962600D01*
X1544100D01*
Y144300D01*
X1060500D01*
G01Y201000D02*
X1544100D01*
G01X1060500Y172650D02*
X1544100D01*
G01X1060500Y257700D02*
X1544100D01*
G01X1060500Y229350D02*
X1544100D01*
G01X1060500Y342750D02*
X1544100D01*
G01X1060500Y314400D02*
X1544100D01*
G01X1060500Y286050D02*
X1544100D01*
G01X1060500Y399450D02*
X1544100D01*
G01X1060500Y371100D02*
X1544100D01*
G01X1060500Y484500D02*
X1544100D01*
G01X1060500Y456150D02*
X1544100D01*
G01X1060500Y427800D02*
X1544100D01*
G01X1060500Y541200D02*
X1544100D01*
G01X1060500Y512850D02*
X1544100D01*
G01X1060500Y626250D02*
X1544100D01*
G01X1060500Y597900D02*
X1544100D01*
G01X1060500Y569550D02*
X1544100D01*
G01X1060500Y682950D02*
X1544100D01*
G01X1060500Y654600D02*
X1544100D01*
G01X1060500Y768000D02*
X1544100D01*
G01X1060500Y739650D02*
X1544100D01*
G01X1060500Y711300D02*
X1544100D01*
G01X1060500Y824700D02*
X1544100D01*
G01X1060500Y796350D02*
X1544100D01*
G01X1071505Y890750D02*
Y903250D01*
X1077395D01*
G01X1075225Y897208D02*
X1071505D01*
G01X1084990Y903250D02*
X1088710D01*
G01X1086850D02*
Y890750D01*
G01X1084990D02*
X1088710D01*
G01X1100180Y897000D02*
X1103280D01*
Y893250D01*
X1102350Y892000D01*
X1101265Y891167D01*
X1099715Y890750D01*
X1098165Y891167D01*
X1097080Y892000D01*
X1096150Y893250D01*
X1095530Y894708D01*
X1095220Y896375D01*
Y897833D01*
X1095530Y899083D01*
X1096150Y900542D01*
X1097080Y901792D01*
X1098010Y902625D01*
X1099250Y903250D01*
X1100335D01*
X1101575Y902833D01*
X1102505Y902000D01*
G01X1108240Y903250D02*
Y894292D01*
X1108860Y892416D01*
X1110100Y891167D01*
X1111650Y890750D01*
X1113200Y891167D01*
X1114440Y892416D01*
X1115060Y894292D01*
Y903250D01*
G01X1120950Y890750D02*
Y903250D01*
X1124825D01*
X1126065Y902625D01*
X1126840Y901792D01*
X1127150Y900125D01*
X1126840Y898458D01*
X1125910Y897417D01*
X1124825Y896792D01*
X1120950D01*
G01X1124825D02*
X1127150Y890750D01*
G01X1139550D02*
X1133350D01*
Y903250D01*
X1139550D01*
G01X1137070Y897208D02*
X1133350D01*
G01X1060500Y909500D02*
X1544100D01*
G01X1060500Y881400D02*
X1544100D01*
G01X1060500Y853050D02*
X1544100D01*
G01X1060500Y937600D02*
X1544100D01*
G01X1080481Y-76304D02*
X1078734Y-76887D01*
X1077424Y-78346D01*
X1076551Y-80095D01*
X1075896Y-82429D01*
X1075678Y-85054D01*
X1075896Y-87679D01*
X1076551Y-90013D01*
X1077424Y-91763D01*
X1078734Y-93221D01*
X1080481Y-93804D01*
X1082227Y-93221D01*
X1083538Y-91763D01*
X1084411Y-90013D01*
X1085066Y-87679D01*
X1085284Y-85054D01*
X1085066Y-82429D01*
X1084411Y-80095D01*
X1083538Y-78346D01*
X1082227Y-76887D01*
X1080481Y-76304D01*
G01X1097981Y-93804D02*
X1099509Y-93512D01*
X1101256Y-92638D01*
X1102348Y-91180D01*
X1102784Y-89137D01*
X1102348Y-87096D01*
X1101038Y-85346D01*
X1099073Y-84471D01*
X1096889D01*
X1095579Y-83887D01*
X1094487Y-82429D01*
X1094051Y-80388D01*
X1094706Y-78346D01*
X1096234Y-76887D01*
X1097981Y-76304D01*
X1099727Y-76887D01*
X1101256Y-78346D01*
X1101911Y-80388D01*
X1101474Y-82429D01*
X1100383Y-83887D01*
X1099073Y-84471D01*
X1096889D01*
X1094924Y-85346D01*
X1093614Y-87096D01*
X1093178Y-89137D01*
X1093614Y-91180D01*
X1094706Y-92638D01*
X1096453Y-93512D01*
X1097981Y-93804D01*
G01X1111551Y-94387D02*
X1119411Y-76304D01*
G01X1132981D02*
X1131234Y-76887D01*
X1129924Y-78346D01*
X1129051Y-80095D01*
X1128396Y-82429D01*
X1128178Y-85054D01*
X1128396Y-87679D01*
X1129051Y-90013D01*
X1129924Y-91763D01*
X1131234Y-93221D01*
X1132981Y-93804D01*
X1134727Y-93221D01*
X1136038Y-91763D01*
X1136911Y-90013D01*
X1137566Y-87679D01*
X1137784Y-85054D01*
X1137566Y-82429D01*
X1136911Y-80095D01*
X1136038Y-78346D01*
X1134727Y-76887D01*
X1132981Y-76304D01*
G01X1150044Y-93804D02*
X1150481Y-90013D01*
X1151136Y-86804D01*
X1152009Y-83887D01*
X1153101Y-80679D01*
X1154848Y-76304D01*
X1146114D01*
G01X1164051Y-94387D02*
X1171911Y-76304D01*
G01X1181333Y-79221D02*
X1182643Y-77471D01*
X1184171Y-76596D01*
X1185918Y-76304D01*
X1188101Y-76887D01*
X1189629Y-78346D01*
X1190066Y-80095D01*
X1189848Y-81846D01*
X1188974Y-83304D01*
X1184608Y-86221D01*
X1182643Y-88262D01*
X1181333Y-91180D01*
X1180896Y-93804D01*
X1190066D01*
G01X1202981Y-76304D02*
X1201234Y-76887D01*
X1199924Y-78346D01*
X1199051Y-80095D01*
X1198396Y-82429D01*
X1198178Y-85054D01*
X1198396Y-87679D01*
X1199051Y-90013D01*
X1199924Y-91763D01*
X1201234Y-93221D01*
X1202981Y-93804D01*
X1204727Y-93221D01*
X1206038Y-91763D01*
X1206911Y-90013D01*
X1207566Y-87679D01*
X1207784Y-85054D01*
X1207566Y-82429D01*
X1206911Y-80095D01*
X1206038Y-78346D01*
X1204727Y-76887D01*
X1202981Y-76304D01*
G01X1220481Y-93804D02*
Y-76304D01*
X1217861Y-79804D01*
G01Y-93804D02*
X1223101D01*
G01X1237544D02*
X1237981Y-90013D01*
X1238636Y-86804D01*
X1239509Y-83887D01*
X1240601Y-80679D01*
X1242348Y-76304D01*
X1233614D01*
G01X1128178Y-48804D02*
Y-31304D01*
X1132544D01*
X1134291Y-32179D01*
X1135601Y-33346D01*
X1136693Y-35095D01*
X1137566Y-37138D01*
X1137784Y-40054D01*
X1137566Y-42971D01*
X1136693Y-45013D01*
X1135601Y-46763D01*
X1134291Y-47929D01*
X1132544Y-48804D01*
X1128178D01*
G01X1154411D02*
Y-37138D01*
G01Y-39179D02*
X1153538Y-38013D01*
X1152227Y-37429D01*
X1150699Y-37138D01*
X1149171Y-37721D01*
X1147861Y-38887D01*
X1146987Y-40637D01*
X1146551Y-42971D01*
X1146987Y-45304D01*
X1147861Y-47054D01*
X1149171Y-48221D01*
X1150699Y-48804D01*
X1152227Y-48512D01*
X1153538Y-47638D01*
X1154411Y-46471D01*
G01X1167981Y-31304D02*
Y-48804D01*
G01X1164924Y-37138D02*
X1171038D01*
G01X1182206Y-40929D02*
X1189193D01*
X1188538Y-38887D01*
X1187446Y-37721D01*
X1185918Y-37138D01*
X1184389Y-37429D01*
X1183079Y-38304D01*
X1182206Y-40346D01*
X1181769Y-42096D01*
Y-43846D01*
X1182206Y-45596D01*
X1183298Y-47346D01*
X1184608Y-48512D01*
X1186136Y-48804D01*
X1187664Y-48221D01*
X1189193Y-46471D01*
G01X1143890Y943850D02*
Y956350D01*
X1146990D01*
X1148230Y955725D01*
X1149160Y954892D01*
X1149935Y953642D01*
X1150555Y952183D01*
X1150710Y950100D01*
X1150555Y948017D01*
X1149935Y946558D01*
X1149160Y945308D01*
X1148230Y944475D01*
X1146990Y943850D01*
X1143890D01*
G01X1156600D02*
Y956350D01*
X1160475D01*
X1161715Y955725D01*
X1162490Y954892D01*
X1162800Y953225D01*
X1162490Y951558D01*
X1161560Y950517D01*
X1160475Y949892D01*
X1156600D01*
G01X1160475D02*
X1162800Y943850D01*
G01X1170240Y956350D02*
X1173960D01*
G01X1172100D02*
Y943850D01*
G01X1170240D02*
X1173960D01*
G01X1181400Y956350D02*
Y943850D01*
X1187600D01*
G01X1193800Y956350D02*
Y943850D01*
X1200000D01*
G01X1225110Y955308D02*
X1224180Y955933D01*
X1223095Y956350D01*
X1221855D01*
X1220460Y955725D01*
X1219375Y954683D01*
X1218600Y953433D01*
X1217980Y951350D01*
X1217825Y949475D01*
X1218135Y947600D01*
X1218600Y946350D01*
X1219530Y945100D01*
X1220615Y944267D01*
X1221700Y943850D01*
X1222785D01*
X1223870Y944267D01*
X1224800Y944891D01*
X1225575Y945725D01*
G01X1230845Y943850D02*
Y956350D01*
G01X1237355D02*
Y943850D01*
G01Y950100D02*
X1230845D01*
G01X1242625Y943850D02*
X1246500Y956350D01*
X1250375Y943850D01*
G01X1248980Y948225D02*
X1244020D01*
G01X1255800Y943850D02*
Y956350D01*
X1259675D01*
X1260915Y955725D01*
X1261690Y954892D01*
X1262000Y953225D01*
X1261690Y951558D01*
X1260760Y950517D01*
X1259675Y949892D01*
X1255800D01*
G01X1259675D02*
X1262000Y943850D01*
G01X1271300Y956350D02*
Y943850D01*
G01X1267735Y956350D02*
X1274865D01*
G01X1283700Y943433D02*
X1283390Y943642D01*
Y944058D01*
X1283700Y944267D01*
X1284010Y944058D01*
Y943642D01*
X1283700Y943433D01*
G01Y949058D02*
X1283390Y949267D01*
Y949683D01*
X1283700Y949892D01*
X1284010Y949683D01*
Y949267D01*
X1283700Y949058D01*
G01X1308500Y956350D02*
Y943850D01*
G01X1304935Y956350D02*
X1312065D01*
G01X1320900Y943850D02*
X1319660Y944058D01*
X1318575Y944891D01*
X1317645Y946142D01*
X1317025Y947600D01*
X1316715Y949267D01*
Y950933D01*
X1317025Y952600D01*
X1317645Y954058D01*
X1318575Y955308D01*
X1319660Y956142D01*
X1320900Y956350D01*
X1322140Y956142D01*
X1323225Y955308D01*
X1324155Y954058D01*
X1324775Y952600D01*
X1325085Y950933D01*
Y949267D01*
X1324775Y947600D01*
X1324155Y946142D01*
X1323225Y944891D01*
X1322140Y944058D01*
X1320900Y943850D01*
G01X1330200D02*
Y956350D01*
X1333920D01*
X1335160Y955725D01*
X1336090Y954267D01*
X1336400Y952600D01*
X1336090Y950933D01*
X1335315Y949683D01*
X1333920Y949058D01*
X1330200D01*
G01X1358100Y956350D02*
Y943850D01*
G01X1355930Y952183D02*
X1360270D01*
G01X1370500Y943850D02*
X1369570Y944058D01*
X1368640Y944891D01*
X1368020Y946350D01*
X1367710Y948017D01*
X1368020Y949683D01*
X1368640Y951142D01*
X1369570Y951975D01*
X1370500Y952183D01*
X1371430Y951975D01*
X1372360Y951142D01*
X1372980Y949683D01*
X1373135Y948017D01*
X1372980Y946350D01*
X1372360Y944891D01*
X1371430Y944058D01*
X1370500Y943850D01*
G01X1396540Y950517D02*
X1397160Y951142D01*
X1397625Y952183D01*
X1397935Y953642D01*
X1397625Y954892D01*
X1397005Y955725D01*
X1395920Y956350D01*
X1391735D01*
Y943850D01*
X1396850D01*
X1397935Y944683D01*
X1398555Y945933D01*
X1398865Y947392D01*
X1398555Y948850D01*
X1397625Y950100D01*
X1396540Y950517D01*
X1391735D01*
G01X1407700Y943850D02*
X1406460Y944058D01*
X1405375Y944891D01*
X1404445Y946142D01*
X1403825Y947600D01*
X1403515Y949267D01*
Y950933D01*
X1403825Y952600D01*
X1404445Y954058D01*
X1405375Y955308D01*
X1406460Y956142D01*
X1407700Y956350D01*
X1408940Y956142D01*
X1410025Y955308D01*
X1410955Y954058D01*
X1411575Y952600D01*
X1411885Y950933D01*
Y949267D01*
X1411575Y947600D01*
X1410955Y946142D01*
X1410025Y944891D01*
X1408940Y944058D01*
X1407700Y943850D01*
G01X1420100Y956350D02*
Y943850D01*
G01X1416535Y956350D02*
X1423665D01*
G01X1432500D02*
Y943850D01*
G01X1428935Y956350D02*
X1436065D01*
G01X1444900Y943850D02*
X1443660Y944058D01*
X1442575Y944891D01*
X1441645Y946142D01*
X1441025Y947600D01*
X1440715Y949267D01*
Y950933D01*
X1441025Y952600D01*
X1441645Y954058D01*
X1442575Y955308D01*
X1443660Y956142D01*
X1444900Y956350D01*
X1446140Y956142D01*
X1447225Y955308D01*
X1448155Y954058D01*
X1448775Y952600D01*
X1449085Y950933D01*
Y949267D01*
X1448775Y947600D01*
X1448155Y946142D01*
X1447225Y944891D01*
X1446140Y944058D01*
X1444900Y943850D01*
G01X1453270D02*
Y956350D01*
X1457300Y945933D01*
X1461330Y956350D01*
Y943850D01*
G01X1195350Y208925D02*
X1196435Y209133D01*
X1197675Y209758D01*
X1198450Y210800D01*
X1198760Y212258D01*
X1198450Y213716D01*
X1197520Y214967D01*
X1196125Y215592D01*
X1194575D01*
X1193645Y216008D01*
X1192870Y217050D01*
X1192560Y218508D01*
X1193025Y219967D01*
X1194110Y221008D01*
X1195350Y221425D01*
X1196590Y221008D01*
X1197675Y219967D01*
X1198140Y218508D01*
X1197830Y217050D01*
X1197055Y216008D01*
X1196125Y215592D01*
X1194575D01*
X1193180Y214967D01*
X1192250Y213716D01*
X1191940Y212258D01*
X1192250Y210800D01*
X1193025Y209758D01*
X1194265Y209133D01*
X1195350Y208925D01*
G01X1204340Y211425D02*
X1205270Y209966D01*
X1206510Y209133D01*
X1207905Y208925D01*
X1209145Y209133D01*
X1210385Y210175D01*
X1211160Y211425D01*
X1211315Y212675D01*
X1211005Y214133D01*
X1209920Y215175D01*
X1208835Y215592D01*
X1207440D01*
G01X1208835D02*
X1209765Y216217D01*
X1210540Y217258D01*
X1210850Y218508D01*
X1210540Y219758D01*
X1209765Y220800D01*
X1208370Y221425D01*
X1206975Y221217D01*
X1205580Y220383D01*
G01X1220150Y208508D02*
X1219840Y208717D01*
Y209133D01*
X1220150Y209342D01*
X1220460Y209133D01*
Y208717D01*
X1220150Y208508D01*
G01X1232550Y221425D02*
X1231310Y221008D01*
X1230380Y219967D01*
X1229760Y218717D01*
X1229295Y217050D01*
X1229140Y215175D01*
X1229295Y213300D01*
X1229760Y211633D01*
X1230380Y210383D01*
X1231310Y209342D01*
X1232550Y208925D01*
X1233790Y209342D01*
X1234720Y210383D01*
X1235340Y211633D01*
X1235805Y213300D01*
X1235960Y215175D01*
X1235805Y217050D01*
X1235340Y218717D01*
X1234720Y219967D01*
X1233790Y221008D01*
X1232550Y221425D01*
G01X1242625Y217258D02*
X1247275Y208925D01*
G01Y217258D02*
X1242625Y208925D01*
G01X1253940Y211425D02*
X1254870Y209966D01*
X1256110Y209133D01*
X1257505Y208925D01*
X1258745Y209133D01*
X1259985Y210175D01*
X1260760Y211425D01*
X1260915Y212675D01*
X1260605Y214133D01*
X1259520Y215175D01*
X1258435Y215592D01*
X1257040D01*
G01X1258435D02*
X1259365Y216217D01*
X1260140Y217258D01*
X1260450Y218508D01*
X1260140Y219758D01*
X1259365Y220800D01*
X1257970Y221425D01*
X1256575Y221217D01*
X1255180Y220383D01*
G01X1266805Y219342D02*
X1267735Y220591D01*
X1268820Y221217D01*
X1270060Y221425D01*
X1271610Y221008D01*
X1272695Y219967D01*
X1273005Y218717D01*
X1272850Y217466D01*
X1272230Y216425D01*
X1269130Y214342D01*
X1267735Y212883D01*
X1266805Y210800D01*
X1266495Y208925D01*
X1273005D01*
G01X1282150Y208508D02*
X1281840Y208717D01*
Y209133D01*
X1282150Y209342D01*
X1282460Y209133D01*
Y208717D01*
X1282150Y208508D01*
G01X1294550Y221425D02*
X1293310Y221008D01*
X1292380Y219967D01*
X1291760Y218717D01*
X1291295Y217050D01*
X1291140Y215175D01*
X1291295Y213300D01*
X1291760Y211633D01*
X1292380Y210383D01*
X1293310Y209342D01*
X1294550Y208925D01*
X1295790Y209342D01*
X1296720Y210383D01*
X1297340Y211633D01*
X1297805Y213300D01*
X1297960Y215175D01*
X1297805Y217050D01*
X1297340Y218717D01*
X1296720Y219967D01*
X1295790Y221008D01*
X1294550Y221425D01*
G01X1182950Y180575D02*
Y193075D01*
X1181090Y190575D01*
G01Y180575D02*
X1184810D01*
G01X1195350D02*
X1196435Y180783D01*
X1197675Y181408D01*
X1198450Y182450D01*
X1198760Y183908D01*
X1198450Y185366D01*
X1197520Y186617D01*
X1196125Y187242D01*
X1194575D01*
X1193645Y187658D01*
X1192870Y188700D01*
X1192560Y190158D01*
X1193025Y191617D01*
X1194110Y192658D01*
X1195350Y193075D01*
X1196590Y192658D01*
X1197675Y191617D01*
X1198140Y190158D01*
X1197830Y188700D01*
X1197055Y187658D01*
X1196125Y187242D01*
X1194575D01*
X1193180Y186617D01*
X1192250Y185366D01*
X1191940Y183908D01*
X1192250Y182450D01*
X1193025Y181408D01*
X1194265Y180783D01*
X1195350Y180575D01*
G01X1205115Y182033D02*
X1206200Y180992D01*
X1207440Y180575D01*
X1208680Y180992D01*
X1209765Y182241D01*
X1210540Y184117D01*
X1210850Y185992D01*
Y188283D01*
X1210540Y190158D01*
X1209765Y191825D01*
X1208835Y192658D01*
X1207750Y193075D01*
X1206510Y192658D01*
X1205580Y191825D01*
X1204960Y190575D01*
X1204650Y188908D01*
X1204960Y187450D01*
X1205735Y185992D01*
X1206665Y185158D01*
X1207750Y184950D01*
X1208990Y185366D01*
X1209920Y186408D01*
X1210850Y188283D01*
G01X1220150Y180158D02*
X1219840Y180367D01*
Y180783D01*
X1220150Y180992D01*
X1220460Y180783D01*
Y180367D01*
X1220150Y180158D01*
G01X1232550Y193075D02*
X1231310Y192658D01*
X1230380Y191617D01*
X1229760Y190367D01*
X1229295Y188700D01*
X1229140Y186825D01*
X1229295Y184950D01*
X1229760Y183283D01*
X1230380Y182033D01*
X1231310Y180992D01*
X1232550Y180575D01*
X1233790Y180992D01*
X1234720Y182033D01*
X1235340Y183283D01*
X1235805Y184950D01*
X1235960Y186825D01*
X1235805Y188700D01*
X1235340Y190367D01*
X1234720Y191617D01*
X1233790Y192658D01*
X1232550Y193075D01*
G01X1242625Y188908D02*
X1247275Y180575D01*
G01Y188908D02*
X1242625Y180575D01*
G01X1257350D02*
Y193075D01*
X1255490Y190575D01*
G01Y180575D02*
X1259210D01*
G01X1266805Y190992D02*
X1267735Y192241D01*
X1268820Y192867D01*
X1270060Y193075D01*
X1271610Y192658D01*
X1272695Y191617D01*
X1273005Y190367D01*
X1272850Y189116D01*
X1272230Y188075D01*
X1269130Y185992D01*
X1267735Y184533D01*
X1266805Y182450D01*
X1266495Y180575D01*
X1273005D01*
G01X1279205Y185783D02*
X1280290Y187242D01*
X1281220Y188075D01*
X1282460Y188492D01*
X1283545Y188075D01*
X1284320Y187242D01*
X1284940Y185992D01*
X1285095Y184533D01*
X1284940Y183283D01*
X1284320Y182033D01*
X1283390Y180992D01*
X1282305Y180575D01*
X1281065Y180992D01*
X1279980Y182241D01*
X1279360Y184117D01*
X1279205Y186200D01*
X1279515Y188908D01*
X1279980Y190367D01*
X1280755Y191825D01*
X1281840Y192867D01*
X1282925Y193075D01*
X1284010Y192658D01*
X1284785Y191617D01*
G01X1294550Y180158D02*
X1294240Y180367D01*
Y180783D01*
X1294550Y180992D01*
X1294860Y180783D01*
Y180367D01*
X1294550Y180158D01*
G01X1306950Y193075D02*
X1305710Y192658D01*
X1304780Y191617D01*
X1304160Y190367D01*
X1303695Y188700D01*
X1303540Y186825D01*
X1303695Y184950D01*
X1304160Y183283D01*
X1304780Y182033D01*
X1305710Y180992D01*
X1306950Y180575D01*
X1308190Y180992D01*
X1309120Y182033D01*
X1309740Y183283D01*
X1310205Y184950D01*
X1310360Y186825D01*
X1310205Y188700D01*
X1309740Y190367D01*
X1309120Y191617D01*
X1308190Y192658D01*
X1306950Y193075D01*
G01X1180005Y162642D02*
X1180935Y163891D01*
X1182020Y164517D01*
X1183260Y164725D01*
X1184810Y164308D01*
X1185895Y163267D01*
X1186205Y162017D01*
X1186050Y160766D01*
X1185430Y159725D01*
X1182330Y157642D01*
X1180935Y156183D01*
X1180005Y154100D01*
X1179695Y152225D01*
X1186205D01*
G01X1192405Y157433D02*
X1193490Y158892D01*
X1194420Y159725D01*
X1195660Y160142D01*
X1196745Y159725D01*
X1197520Y158892D01*
X1198140Y157642D01*
X1198295Y156183D01*
X1198140Y154933D01*
X1197520Y153683D01*
X1196590Y152642D01*
X1195505Y152225D01*
X1194265Y152642D01*
X1193180Y153891D01*
X1192560Y155767D01*
X1192405Y157850D01*
X1192715Y160558D01*
X1193180Y162017D01*
X1193955Y163475D01*
X1195040Y164517D01*
X1196125Y164725D01*
X1197210Y164308D01*
X1197985Y163267D01*
G01X1207750Y152225D02*
X1208835Y152433D01*
X1210075Y153058D01*
X1210850Y154100D01*
X1211160Y155558D01*
X1210850Y157016D01*
X1209920Y158267D01*
X1208525Y158892D01*
X1206975D01*
X1206045Y159308D01*
X1205270Y160350D01*
X1204960Y161808D01*
X1205425Y163267D01*
X1206510Y164308D01*
X1207750Y164725D01*
X1208990Y164308D01*
X1210075Y163267D01*
X1210540Y161808D01*
X1210230Y160350D01*
X1209455Y159308D01*
X1208525Y158892D01*
X1206975D01*
X1205580Y158267D01*
X1204650Y157016D01*
X1204340Y155558D01*
X1204650Y154100D01*
X1205425Y153058D01*
X1206665Y152433D01*
X1207750Y152225D01*
G01X1220150Y151808D02*
X1219840Y152017D01*
Y152433D01*
X1220150Y152642D01*
X1220460Y152433D01*
Y152017D01*
X1220150Y151808D01*
G01X1232550Y164725D02*
X1231310Y164308D01*
X1230380Y163267D01*
X1229760Y162017D01*
X1229295Y160350D01*
X1229140Y158475D01*
X1229295Y156600D01*
X1229760Y154933D01*
X1230380Y153683D01*
X1231310Y152642D01*
X1232550Y152225D01*
X1233790Y152642D01*
X1234720Y153683D01*
X1235340Y154933D01*
X1235805Y156600D01*
X1235960Y158475D01*
X1235805Y160350D01*
X1235340Y162017D01*
X1234720Y163267D01*
X1233790Y164308D01*
X1232550Y164725D01*
G01X1242625Y160558D02*
X1247275Y152225D01*
G01Y160558D02*
X1242625Y152225D01*
G01X1257350D02*
Y164725D01*
X1255490Y162225D01*
G01Y152225D02*
X1259210D01*
G01X1266340Y154725D02*
X1267270Y153266D01*
X1268510Y152433D01*
X1269905Y152225D01*
X1271145Y152433D01*
X1272385Y153475D01*
X1273160Y154725D01*
X1273315Y155975D01*
X1273005Y157433D01*
X1271920Y158475D01*
X1270835Y158892D01*
X1269440D01*
G01X1270835D02*
X1271765Y159517D01*
X1272540Y160558D01*
X1272850Y161808D01*
X1272540Y163058D01*
X1271765Y164100D01*
X1270370Y164725D01*
X1268975Y164517D01*
X1267580Y163683D01*
G01X1284010Y152225D02*
Y164725D01*
X1278275Y155767D01*
X1286025D01*
G01X1294550Y151808D02*
X1294240Y152017D01*
Y152433D01*
X1294550Y152642D01*
X1294860Y152433D01*
Y152017D01*
X1294550Y151808D01*
G01X1306950Y164725D02*
X1305710Y164308D01*
X1304780Y163267D01*
X1304160Y162017D01*
X1303695Y160350D01*
X1303540Y158475D01*
X1303695Y156600D01*
X1304160Y154933D01*
X1304780Y153683D01*
X1305710Y152642D01*
X1306950Y152225D01*
X1308190Y152642D01*
X1309120Y153683D01*
X1309740Y154933D01*
X1310205Y156600D01*
X1310360Y158475D01*
X1310205Y160350D01*
X1309740Y162017D01*
X1309120Y163267D01*
X1308190Y164308D01*
X1306950Y164725D01*
G01X1150400Y909500D02*
Y144300D01*
G01X1220150Y265625D02*
Y278125D01*
X1218290Y275625D01*
G01Y265625D02*
X1222010D01*
G01X1229140Y268125D02*
X1230070Y266666D01*
X1231310Y265833D01*
X1232705Y265625D01*
X1233945Y265833D01*
X1235185Y266875D01*
X1235960Y268125D01*
X1236115Y269375D01*
X1235805Y270833D01*
X1234720Y271875D01*
X1233635Y272292D01*
X1232240D01*
G01X1233635D02*
X1234565Y272917D01*
X1235340Y273958D01*
X1235650Y275208D01*
X1235340Y276458D01*
X1234565Y277500D01*
X1233170Y278125D01*
X1231775Y277917D01*
X1230380Y277083D01*
G01X1244950Y278125D02*
X1243710Y277708D01*
X1242780Y276667D01*
X1242160Y275417D01*
X1241695Y273750D01*
X1241540Y271875D01*
X1241695Y270000D01*
X1242160Y268333D01*
X1242780Y267083D01*
X1243710Y266042D01*
X1244950Y265625D01*
X1246190Y266042D01*
X1247120Y267083D01*
X1247740Y268333D01*
X1248205Y270000D01*
X1248360Y271875D01*
X1248205Y273750D01*
X1247740Y275417D01*
X1247120Y276667D01*
X1246190Y277708D01*
X1244950Y278125D01*
G01X1257350Y265208D02*
X1257040Y265417D01*
Y265833D01*
X1257350Y266042D01*
X1257660Y265833D01*
Y265417D01*
X1257350Y265208D01*
G01X1269750Y278125D02*
X1268510Y277708D01*
X1267580Y276667D01*
X1266960Y275417D01*
X1266495Y273750D01*
X1266340Y271875D01*
X1266495Y270000D01*
X1266960Y268333D01*
X1267580Y267083D01*
X1268510Y266042D01*
X1269750Y265625D01*
X1270990Y266042D01*
X1271920Y267083D01*
X1272540Y268333D01*
X1273005Y270000D01*
X1273160Y271875D01*
X1273005Y273750D01*
X1272540Y275417D01*
X1271920Y276667D01*
X1270990Y277708D01*
X1269750Y278125D01*
G01X1191940Y239150D02*
X1192870Y238108D01*
X1193955Y237483D01*
X1195350Y237275D01*
X1196745Y237692D01*
X1197830Y238525D01*
X1198605Y239983D01*
X1198760Y241650D01*
X1198450Y243317D01*
X1197675Y244358D01*
X1196590Y245192D01*
X1195505Y245400D01*
X1194420Y245192D01*
X1193025Y244358D01*
X1193490Y249775D01*
X1197675D01*
G01X1204805Y242483D02*
X1205890Y243942D01*
X1206820Y244775D01*
X1208060Y245192D01*
X1209145Y244775D01*
X1209920Y243942D01*
X1210540Y242692D01*
X1210695Y241233D01*
X1210540Y239983D01*
X1209920Y238733D01*
X1208990Y237692D01*
X1207905Y237275D01*
X1206665Y237692D01*
X1205580Y238941D01*
X1204960Y240817D01*
X1204805Y242900D01*
X1205115Y245608D01*
X1205580Y247067D01*
X1206355Y248525D01*
X1207440Y249567D01*
X1208525Y249775D01*
X1209610Y249358D01*
X1210385Y248317D01*
G01X1220150Y236858D02*
X1219840Y237067D01*
Y237483D01*
X1220150Y237692D01*
X1220460Y237483D01*
Y237067D01*
X1220150Y236858D01*
G01X1232550Y249775D02*
X1231310Y249358D01*
X1230380Y248317D01*
X1229760Y247067D01*
X1229295Y245400D01*
X1229140Y243525D01*
X1229295Y241650D01*
X1229760Y239983D01*
X1230380Y238733D01*
X1231310Y237692D01*
X1232550Y237275D01*
X1233790Y237692D01*
X1234720Y238733D01*
X1235340Y239983D01*
X1235805Y241650D01*
X1235960Y243525D01*
X1235805Y245400D01*
X1235340Y247067D01*
X1234720Y248317D01*
X1233790Y249358D01*
X1232550Y249775D01*
G01X1242625Y245608D02*
X1247275Y237275D01*
G01Y245608D02*
X1242625Y237275D01*
G01X1253940Y239775D02*
X1254870Y238316D01*
X1256110Y237483D01*
X1257505Y237275D01*
X1258745Y237483D01*
X1259985Y238525D01*
X1260760Y239775D01*
X1260915Y241025D01*
X1260605Y242483D01*
X1259520Y243525D01*
X1258435Y243942D01*
X1257040D01*
G01X1258435D02*
X1259365Y244567D01*
X1260140Y245608D01*
X1260450Y246858D01*
X1260140Y248108D01*
X1259365Y249150D01*
X1257970Y249775D01*
X1256575Y249567D01*
X1255180Y248733D01*
G01X1266805Y247692D02*
X1267735Y248941D01*
X1268820Y249567D01*
X1270060Y249775D01*
X1271610Y249358D01*
X1272695Y248317D01*
X1273005Y247067D01*
X1272850Y245816D01*
X1272230Y244775D01*
X1269130Y242692D01*
X1267735Y241233D01*
X1266805Y239150D01*
X1266495Y237275D01*
X1273005D01*
G01X1282150Y236858D02*
X1281840Y237067D01*
Y237483D01*
X1282150Y237692D01*
X1282460Y237483D01*
Y237067D01*
X1282150Y236858D01*
G01X1294550Y249775D02*
X1293310Y249358D01*
X1292380Y248317D01*
X1291760Y247067D01*
X1291295Y245400D01*
X1291140Y243525D01*
X1291295Y241650D01*
X1291760Y239983D01*
X1292380Y238733D01*
X1293310Y237692D01*
X1294550Y237275D01*
X1295790Y237692D01*
X1296720Y238733D01*
X1297340Y239983D01*
X1297805Y241650D01*
X1297960Y243525D01*
X1297805Y245400D01*
X1297340Y247067D01*
X1296720Y248317D01*
X1295790Y249358D01*
X1294550Y249775D01*
G01X1220150Y549125D02*
Y561625D01*
X1218290Y559125D01*
G01Y549125D02*
X1222010D01*
G01X1229140Y551000D02*
X1230070Y549958D01*
X1231155Y549333D01*
X1232550Y549125D01*
X1233945Y549542D01*
X1235030Y550375D01*
X1235805Y551833D01*
X1235960Y553500D01*
X1235650Y555167D01*
X1234875Y556208D01*
X1233790Y557042D01*
X1232705Y557250D01*
X1231620Y557042D01*
X1230225Y556208D01*
X1230690Y561625D01*
X1234875D01*
G01X1244950Y549125D02*
X1246035Y549333D01*
X1247275Y549958D01*
X1248050Y551000D01*
X1248360Y552458D01*
X1248050Y553916D01*
X1247120Y555167D01*
X1245725Y555792D01*
X1244175D01*
X1243245Y556208D01*
X1242470Y557250D01*
X1242160Y558708D01*
X1242625Y560167D01*
X1243710Y561208D01*
X1244950Y561625D01*
X1246190Y561208D01*
X1247275Y560167D01*
X1247740Y558708D01*
X1247430Y557250D01*
X1246655Y556208D01*
X1245725Y555792D01*
X1244175D01*
X1242780Y555167D01*
X1241850Y553916D01*
X1241540Y552458D01*
X1241850Y551000D01*
X1242625Y549958D01*
X1243865Y549333D01*
X1244950Y549125D01*
G01X1257350Y548708D02*
X1257040Y548917D01*
Y549333D01*
X1257350Y549542D01*
X1257660Y549333D01*
Y548917D01*
X1257350Y548708D01*
G01X1269750Y561625D02*
X1268510Y561208D01*
X1267580Y560167D01*
X1266960Y558917D01*
X1266495Y557250D01*
X1266340Y555375D01*
X1266495Y553500D01*
X1266960Y551833D01*
X1267580Y550583D01*
X1268510Y549542D01*
X1269750Y549125D01*
X1270990Y549542D01*
X1271920Y550583D01*
X1272540Y551833D01*
X1273005Y553500D01*
X1273160Y555375D01*
X1273005Y557250D01*
X1272540Y558917D01*
X1271920Y560167D01*
X1270990Y561208D01*
X1269750Y561625D01*
G01X1220150Y520775D02*
Y533275D01*
X1218290Y530775D01*
G01Y520775D02*
X1222010D01*
G01X1229605Y525983D02*
X1230690Y527442D01*
X1231620Y528275D01*
X1232860Y528692D01*
X1233945Y528275D01*
X1234720Y527442D01*
X1235340Y526192D01*
X1235495Y524733D01*
X1235340Y523483D01*
X1234720Y522233D01*
X1233790Y521192D01*
X1232705Y520775D01*
X1231465Y521192D01*
X1230380Y522441D01*
X1229760Y524317D01*
X1229605Y526400D01*
X1229915Y529108D01*
X1230380Y530567D01*
X1231155Y532025D01*
X1232240Y533067D01*
X1233325Y533275D01*
X1234410Y532858D01*
X1235185Y531817D01*
G01X1244950Y520775D02*
X1246035Y520983D01*
X1247275Y521608D01*
X1248050Y522650D01*
X1248360Y524108D01*
X1248050Y525566D01*
X1247120Y526817D01*
X1245725Y527442D01*
X1244175D01*
X1243245Y527858D01*
X1242470Y528900D01*
X1242160Y530358D01*
X1242625Y531817D01*
X1243710Y532858D01*
X1244950Y533275D01*
X1246190Y532858D01*
X1247275Y531817D01*
X1247740Y530358D01*
X1247430Y528900D01*
X1246655Y527858D01*
X1245725Y527442D01*
X1244175D01*
X1242780Y526817D01*
X1241850Y525566D01*
X1241540Y524108D01*
X1241850Y522650D01*
X1242625Y521608D01*
X1243865Y520983D01*
X1244950Y520775D01*
G01X1257350Y520358D02*
X1257040Y520567D01*
Y520983D01*
X1257350Y521192D01*
X1257660Y520983D01*
Y520567D01*
X1257350Y520358D01*
G01X1269750Y533275D02*
X1268510Y532858D01*
X1267580Y531817D01*
X1266960Y530567D01*
X1266495Y528900D01*
X1266340Y527025D01*
X1266495Y525150D01*
X1266960Y523483D01*
X1267580Y522233D01*
X1268510Y521192D01*
X1269750Y520775D01*
X1270990Y521192D01*
X1271920Y522233D01*
X1272540Y523483D01*
X1273005Y525150D01*
X1273160Y527025D01*
X1273005Y528900D01*
X1272540Y530567D01*
X1271920Y531817D01*
X1270990Y532858D01*
X1269750Y533275D01*
G01X1220150Y577475D02*
Y589975D01*
X1218290Y587475D01*
G01Y577475D02*
X1222010D01*
G01X1229140Y579975D02*
X1230070Y578516D01*
X1231310Y577683D01*
X1232705Y577475D01*
X1233945Y577683D01*
X1235185Y578725D01*
X1235960Y579975D01*
X1236115Y581225D01*
X1235805Y582683D01*
X1234720Y583725D01*
X1233635Y584142D01*
X1232240D01*
G01X1233635D02*
X1234565Y584767D01*
X1235340Y585808D01*
X1235650Y587058D01*
X1235340Y588308D01*
X1234565Y589350D01*
X1233170Y589975D01*
X1231775Y589767D01*
X1230380Y588933D01*
G01X1244950Y577475D02*
X1246035Y577683D01*
X1247275Y578308D01*
X1248050Y579350D01*
X1248360Y580808D01*
X1248050Y582266D01*
X1247120Y583517D01*
X1245725Y584142D01*
X1244175D01*
X1243245Y584558D01*
X1242470Y585600D01*
X1242160Y587058D01*
X1242625Y588517D01*
X1243710Y589558D01*
X1244950Y589975D01*
X1246190Y589558D01*
X1247275Y588517D01*
X1247740Y587058D01*
X1247430Y585600D01*
X1246655Y584558D01*
X1245725Y584142D01*
X1244175D01*
X1242780Y583517D01*
X1241850Y582266D01*
X1241540Y580808D01*
X1241850Y579350D01*
X1242625Y578308D01*
X1243865Y577683D01*
X1244950Y577475D01*
G01X1257350Y577058D02*
X1257040Y577267D01*
Y577683D01*
X1257350Y577892D01*
X1257660Y577683D01*
Y577267D01*
X1257350Y577058D01*
G01X1269750Y589975D02*
X1268510Y589558D01*
X1267580Y588517D01*
X1266960Y587267D01*
X1266495Y585600D01*
X1266340Y583725D01*
X1266495Y581850D01*
X1266960Y580183D01*
X1267580Y578933D01*
X1268510Y577892D01*
X1269750Y577475D01*
X1270990Y577892D01*
X1271920Y578933D01*
X1272540Y580183D01*
X1273005Y581850D01*
X1273160Y583725D01*
X1273005Y585600D01*
X1272540Y587267D01*
X1271920Y588517D01*
X1270990Y589558D01*
X1269750Y589975D01*
G01X1220150Y719225D02*
Y731725D01*
X1218290Y729225D01*
G01Y719225D02*
X1222010D01*
G01X1234410D02*
Y731725D01*
X1228675Y722767D01*
X1236425D01*
G01X1244950Y718808D02*
X1244640Y719017D01*
Y719433D01*
X1244950Y719642D01*
X1245260Y719433D01*
Y719017D01*
X1244950Y718808D01*
G01X1257350Y719225D02*
Y731725D01*
X1255490Y729225D01*
G01Y719225D02*
X1259210D01*
G01X1269440D02*
X1269750Y721933D01*
X1270215Y724225D01*
X1270835Y726308D01*
X1271610Y728600D01*
X1272850Y731725D01*
X1266650D01*
G01X1174425Y918850D02*
X1178300Y931350D01*
X1182175Y918850D01*
G01X1180780Y923225D02*
X1175820D01*
G01X1187600Y931350D02*
Y918850D01*
X1193800D01*
G01X1200000Y931350D02*
Y918850D01*
X1206200D01*
G01X1224490Y931350D02*
Y922392D01*
X1225110Y920516D01*
X1226350Y919267D01*
X1227900Y918850D01*
X1229450Y919267D01*
X1230690Y920516D01*
X1231310Y922392D01*
Y931350D01*
G01X1236735Y918850D02*
Y931350D01*
X1243865Y918850D01*
Y931350D01*
G01X1250840D02*
X1254560D01*
G01X1252700D02*
Y918850D01*
G01X1250840D02*
X1254560D01*
G01X1265100Y931350D02*
Y918850D01*
G01X1261535Y931350D02*
X1268665D01*
G01X1274245Y920516D02*
X1275485Y919475D01*
X1276880Y918850D01*
X1278120D01*
X1279360Y919475D01*
X1280290Y920516D01*
X1280755Y921975D01*
X1280445Y923433D01*
X1279670Y924683D01*
X1278275Y925517D01*
X1276415Y925933D01*
X1275330Y926767D01*
X1274865Y928225D01*
X1275175Y929683D01*
X1275950Y930725D01*
X1277035Y931350D01*
X1278120D01*
X1279205Y930933D01*
X1280135Y929892D01*
G01X1298425Y918850D02*
X1302300Y931350D01*
X1306175Y918850D01*
G01X1304780Y923225D02*
X1299820D01*
G01X1311600Y918850D02*
Y931350D01*
X1315475D01*
X1316715Y930725D01*
X1317490Y929892D01*
X1317800Y928225D01*
X1317490Y926558D01*
X1316560Y925517D01*
X1315475Y924892D01*
X1311600D01*
G01X1315475D02*
X1317800Y918850D01*
G01X1330200D02*
X1324000D01*
Y931350D01*
X1330200D01*
G01X1327720Y925308D02*
X1324000D01*
G01X1350040Y931350D02*
X1353760D01*
G01X1351900D02*
Y918850D01*
G01X1350040D02*
X1353760D01*
G01X1360735D02*
Y931350D01*
X1367865Y918850D01*
Y931350D01*
G01X1385070Y918850D02*
Y931350D01*
X1389100Y920933D01*
X1393130Y931350D01*
Y918850D01*
G01X1399640Y931350D02*
X1403360D01*
G01X1401500D02*
Y918850D01*
G01X1399640D02*
X1403360D01*
G01X1410800Y931350D02*
Y918850D01*
X1417000D01*
G01X1423045Y920516D02*
X1424285Y919475D01*
X1425680Y918850D01*
X1426920D01*
X1428160Y919475D01*
X1429090Y920516D01*
X1429555Y921975D01*
X1429245Y923433D01*
X1428470Y924683D01*
X1427075Y925517D01*
X1425215Y925933D01*
X1424130Y926767D01*
X1423665Y928225D01*
X1423975Y929683D01*
X1424750Y930725D01*
X1425835Y931350D01*
X1426920D01*
X1428005Y930933D01*
X1428935Y929892D01*
G01X1226350Y350675D02*
X1227435Y350883D01*
X1228675Y351508D01*
X1229450Y352550D01*
X1229760Y354008D01*
X1229450Y355466D01*
X1228520Y356717D01*
X1227125Y357342D01*
X1225575D01*
X1224645Y357758D01*
X1223870Y358800D01*
X1223560Y360258D01*
X1224025Y361717D01*
X1225110Y362758D01*
X1226350Y363175D01*
X1227590Y362758D01*
X1228675Y361717D01*
X1229140Y360258D01*
X1228830Y358800D01*
X1228055Y357758D01*
X1227125Y357342D01*
X1225575D01*
X1224180Y356717D01*
X1223250Y355466D01*
X1222940Y354008D01*
X1223250Y352550D01*
X1224025Y351508D01*
X1225265Y350883D01*
X1226350Y350675D01*
G01X1235805Y355883D02*
X1236890Y357342D01*
X1237820Y358175D01*
X1239060Y358592D01*
X1240145Y358175D01*
X1240920Y357342D01*
X1241540Y356092D01*
X1241695Y354633D01*
X1241540Y353383D01*
X1240920Y352133D01*
X1239990Y351092D01*
X1238905Y350675D01*
X1237665Y351092D01*
X1236580Y352341D01*
X1235960Y354217D01*
X1235805Y356300D01*
X1236115Y359008D01*
X1236580Y360467D01*
X1237355Y361925D01*
X1238440Y362967D01*
X1239525Y363175D01*
X1240610Y362758D01*
X1241385Y361717D01*
G01X1251150Y350258D02*
X1250840Y350467D01*
Y350883D01*
X1251150Y351092D01*
X1251460Y350883D01*
Y350467D01*
X1251150Y350258D01*
G01X1263550Y363175D02*
X1262310Y362758D01*
X1261380Y361717D01*
X1260760Y360467D01*
X1260295Y358800D01*
X1260140Y356925D01*
X1260295Y355050D01*
X1260760Y353383D01*
X1261380Y352133D01*
X1262310Y351092D01*
X1263550Y350675D01*
X1264790Y351092D01*
X1265720Y352133D01*
X1266340Y353383D01*
X1266805Y355050D01*
X1266960Y356925D01*
X1266805Y358800D01*
X1266340Y360467D01*
X1265720Y361717D01*
X1264790Y362758D01*
X1263550Y363175D01*
G01X1223715Y323783D02*
X1224800Y322742D01*
X1226040Y322325D01*
X1227280Y322742D01*
X1228365Y323991D01*
X1229140Y325867D01*
X1229450Y327742D01*
Y330033D01*
X1229140Y331908D01*
X1228365Y333575D01*
X1227435Y334408D01*
X1226350Y334825D01*
X1225110Y334408D01*
X1224180Y333575D01*
X1223560Y332325D01*
X1223250Y330658D01*
X1223560Y329200D01*
X1224335Y327742D01*
X1225265Y326908D01*
X1226350Y326700D01*
X1227590Y327116D01*
X1228520Y328158D01*
X1229450Y330033D01*
G01X1240610Y322325D02*
Y334825D01*
X1234875Y325867D01*
X1242625D01*
G01X1251150Y321908D02*
X1250840Y322117D01*
Y322533D01*
X1251150Y322742D01*
X1251460Y322533D01*
Y322117D01*
X1251150Y321908D01*
G01X1263550Y334825D02*
X1262310Y334408D01*
X1261380Y333367D01*
X1260760Y332117D01*
X1260295Y330450D01*
X1260140Y328575D01*
X1260295Y326700D01*
X1260760Y325033D01*
X1261380Y323783D01*
X1262310Y322742D01*
X1263550Y322325D01*
X1264790Y322742D01*
X1265720Y323783D01*
X1266340Y325033D01*
X1266805Y326700D01*
X1266960Y328575D01*
X1266805Y330450D01*
X1266340Y332117D01*
X1265720Y333367D01*
X1264790Y334408D01*
X1263550Y334825D01*
G01X1223715Y295433D02*
X1224800Y294392D01*
X1226040Y293975D01*
X1227280Y294392D01*
X1228365Y295641D01*
X1229140Y297517D01*
X1229450Y299392D01*
Y301683D01*
X1229140Y303558D01*
X1228365Y305225D01*
X1227435Y306058D01*
X1226350Y306475D01*
X1225110Y306058D01*
X1224180Y305225D01*
X1223560Y303975D01*
X1223250Y302308D01*
X1223560Y300850D01*
X1224335Y299392D01*
X1225265Y298558D01*
X1226350Y298350D01*
X1227590Y298766D01*
X1228520Y299808D01*
X1229450Y301683D01*
G01X1238440Y293975D02*
X1238750Y296683D01*
X1239215Y298975D01*
X1239835Y301058D01*
X1240610Y303350D01*
X1241850Y306475D01*
X1235650D01*
G01X1251150Y293558D02*
X1250840Y293767D01*
Y294183D01*
X1251150Y294392D01*
X1251460Y294183D01*
Y293767D01*
X1251150Y293558D01*
G01X1263550Y306475D02*
X1262310Y306058D01*
X1261380Y305017D01*
X1260760Y303767D01*
X1260295Y302100D01*
X1260140Y300225D01*
X1260295Y298350D01*
X1260760Y296683D01*
X1261380Y295433D01*
X1262310Y294392D01*
X1263550Y293975D01*
X1264790Y294392D01*
X1265720Y295433D01*
X1266340Y296683D01*
X1266805Y298350D01*
X1266960Y300225D01*
X1266805Y302100D01*
X1266340Y303767D01*
X1265720Y305017D01*
X1264790Y306058D01*
X1263550Y306475D01*
G01X1228210Y407375D02*
Y419875D01*
X1222475Y410917D01*
X1230225D01*
G01X1238750Y407375D02*
X1239835Y407583D01*
X1241075Y408208D01*
X1241850Y409250D01*
X1242160Y410708D01*
X1241850Y412166D01*
X1240920Y413417D01*
X1239525Y414042D01*
X1237975D01*
X1237045Y414458D01*
X1236270Y415500D01*
X1235960Y416958D01*
X1236425Y418417D01*
X1237510Y419458D01*
X1238750Y419875D01*
X1239990Y419458D01*
X1241075Y418417D01*
X1241540Y416958D01*
X1241230Y415500D01*
X1240455Y414458D01*
X1239525Y414042D01*
X1237975D01*
X1236580Y413417D01*
X1235650Y412166D01*
X1235340Y410708D01*
X1235650Y409250D01*
X1236425Y408208D01*
X1237665Y407583D01*
X1238750Y407375D01*
G01X1251150Y406958D02*
X1250840Y407167D01*
Y407583D01*
X1251150Y407792D01*
X1251460Y407583D01*
Y407167D01*
X1251150Y406958D01*
G01X1263550Y419875D02*
X1262310Y419458D01*
X1261380Y418417D01*
X1260760Y417167D01*
X1260295Y415500D01*
X1260140Y413625D01*
X1260295Y411750D01*
X1260760Y410083D01*
X1261380Y408833D01*
X1262310Y407792D01*
X1263550Y407375D01*
X1264790Y407792D01*
X1265720Y408833D01*
X1266340Y410083D01*
X1266805Y411750D01*
X1266960Y413625D01*
X1266805Y415500D01*
X1266340Y417167D01*
X1265720Y418417D01*
X1264790Y419458D01*
X1263550Y419875D01*
G01X1223405Y384233D02*
X1224490Y385692D01*
X1225420Y386525D01*
X1226660Y386942D01*
X1227745Y386525D01*
X1228520Y385692D01*
X1229140Y384442D01*
X1229295Y382983D01*
X1229140Y381733D01*
X1228520Y380483D01*
X1227590Y379442D01*
X1226505Y379025D01*
X1225265Y379442D01*
X1224180Y380691D01*
X1223560Y382567D01*
X1223405Y384650D01*
X1223715Y387358D01*
X1224180Y388817D01*
X1224955Y390275D01*
X1226040Y391317D01*
X1227125Y391525D01*
X1228210Y391108D01*
X1228985Y390067D01*
G01X1235340Y381525D02*
X1236270Y380066D01*
X1237510Y379233D01*
X1238905Y379025D01*
X1240145Y379233D01*
X1241385Y380275D01*
X1242160Y381525D01*
X1242315Y382775D01*
X1242005Y384233D01*
X1240920Y385275D01*
X1239835Y385692D01*
X1238440D01*
G01X1239835D02*
X1240765Y386317D01*
X1241540Y387358D01*
X1241850Y388608D01*
X1241540Y389858D01*
X1240765Y390900D01*
X1239370Y391525D01*
X1237975Y391317D01*
X1236580Y390483D01*
G01X1251150Y378608D02*
X1250840Y378817D01*
Y379233D01*
X1251150Y379442D01*
X1251460Y379233D01*
Y378817D01*
X1251150Y378608D01*
G01X1263550Y391525D02*
X1262310Y391108D01*
X1261380Y390067D01*
X1260760Y388817D01*
X1260295Y387150D01*
X1260140Y385275D01*
X1260295Y383400D01*
X1260760Y381733D01*
X1261380Y380483D01*
X1262310Y379442D01*
X1263550Y379025D01*
X1264790Y379442D01*
X1265720Y380483D01*
X1266340Y381733D01*
X1266805Y383400D01*
X1266960Y385275D01*
X1266805Y387150D01*
X1266340Y388817D01*
X1265720Y390067D01*
X1264790Y391108D01*
X1263550Y391525D01*
G01X1222940Y494925D02*
X1223870Y493466D01*
X1225110Y492633D01*
X1226505Y492425D01*
X1227745Y492633D01*
X1228985Y493675D01*
X1229760Y494925D01*
X1229915Y496175D01*
X1229605Y497633D01*
X1228520Y498675D01*
X1227435Y499092D01*
X1226040D01*
G01X1227435D02*
X1228365Y499717D01*
X1229140Y500758D01*
X1229450Y502008D01*
X1229140Y503258D01*
X1228365Y504300D01*
X1226970Y504925D01*
X1225575Y504717D01*
X1224180Y503883D01*
G01X1235805Y502842D02*
X1236735Y504091D01*
X1237820Y504717D01*
X1239060Y504925D01*
X1240610Y504508D01*
X1241695Y503467D01*
X1242005Y502217D01*
X1241850Y500966D01*
X1241230Y499925D01*
X1238130Y497842D01*
X1236735Y496383D01*
X1235805Y494300D01*
X1235495Y492425D01*
X1242005D01*
G01X1251150Y492008D02*
X1250840Y492217D01*
Y492633D01*
X1251150Y492842D01*
X1251460Y492633D01*
Y492217D01*
X1251150Y492008D01*
G01X1263550Y504925D02*
X1262310Y504508D01*
X1261380Y503467D01*
X1260760Y502217D01*
X1260295Y500550D01*
X1260140Y498675D01*
X1260295Y496800D01*
X1260760Y495133D01*
X1261380Y493883D01*
X1262310Y492842D01*
X1263550Y492425D01*
X1264790Y492842D01*
X1265720Y493883D01*
X1266340Y495133D01*
X1266805Y496800D01*
X1266960Y498675D01*
X1266805Y500550D01*
X1266340Y502217D01*
X1265720Y503467D01*
X1264790Y504508D01*
X1263550Y504925D01*
G01X1222940Y466575D02*
X1223870Y465116D01*
X1225110Y464283D01*
X1226505Y464075D01*
X1227745Y464283D01*
X1228985Y465325D01*
X1229760Y466575D01*
X1229915Y467825D01*
X1229605Y469283D01*
X1228520Y470325D01*
X1227435Y470742D01*
X1226040D01*
G01X1227435D02*
X1228365Y471367D01*
X1229140Y472408D01*
X1229450Y473658D01*
X1229140Y474908D01*
X1228365Y475950D01*
X1226970Y476575D01*
X1225575Y476367D01*
X1224180Y475533D01*
G01X1240610Y464075D02*
Y476575D01*
X1234875Y467617D01*
X1242625D01*
G01X1251150Y463658D02*
X1250840Y463867D01*
Y464283D01*
X1251150Y464492D01*
X1251460Y464283D01*
Y463867D01*
X1251150Y463658D01*
G01X1263550Y476575D02*
X1262310Y476158D01*
X1261380Y475117D01*
X1260760Y473867D01*
X1260295Y472200D01*
X1260140Y470325D01*
X1260295Y468450D01*
X1260760Y466783D01*
X1261380Y465533D01*
X1262310Y464492D01*
X1263550Y464075D01*
X1264790Y464492D01*
X1265720Y465533D01*
X1266340Y466783D01*
X1266805Y468450D01*
X1266960Y470325D01*
X1266805Y472200D01*
X1266340Y473867D01*
X1265720Y475117D01*
X1264790Y476158D01*
X1263550Y476575D01*
G01X1228210Y435725D02*
Y448225D01*
X1222475Y439267D01*
X1230225D01*
G01X1240610Y435725D02*
Y448225D01*
X1234875Y439267D01*
X1242625D01*
G01X1251150Y435308D02*
X1250840Y435517D01*
Y435933D01*
X1251150Y436142D01*
X1251460Y435933D01*
Y435517D01*
X1251150Y435308D01*
G01X1263550Y448225D02*
X1262310Y447808D01*
X1261380Y446767D01*
X1260760Y445517D01*
X1260295Y443850D01*
X1260140Y441975D01*
X1260295Y440100D01*
X1260760Y438433D01*
X1261380Y437183D01*
X1262310Y436142D01*
X1263550Y435725D01*
X1264790Y436142D01*
X1265720Y437183D01*
X1266340Y438433D01*
X1266805Y440100D01*
X1266960Y441975D01*
X1266805Y443850D01*
X1266340Y445517D01*
X1265720Y446767D01*
X1264790Y447808D01*
X1263550Y448225D01*
G01X1222940Y636675D02*
X1223870Y635216D01*
X1225110Y634383D01*
X1226505Y634175D01*
X1227745Y634383D01*
X1228985Y635425D01*
X1229760Y636675D01*
X1229915Y637925D01*
X1229605Y639383D01*
X1228520Y640425D01*
X1227435Y640842D01*
X1226040D01*
G01X1227435D02*
X1228365Y641467D01*
X1229140Y642508D01*
X1229450Y643758D01*
X1229140Y645008D01*
X1228365Y646050D01*
X1226970Y646675D01*
X1225575Y646467D01*
X1224180Y645633D01*
G01X1235340Y636050D02*
X1236270Y635008D01*
X1237355Y634383D01*
X1238750Y634175D01*
X1240145Y634592D01*
X1241230Y635425D01*
X1242005Y636883D01*
X1242160Y638550D01*
X1241850Y640217D01*
X1241075Y641258D01*
X1239990Y642092D01*
X1238905Y642300D01*
X1237820Y642092D01*
X1236425Y641258D01*
X1236890Y646675D01*
X1241075D01*
G01X1251150Y633758D02*
X1250840Y633967D01*
Y634383D01*
X1251150Y634592D01*
X1251460Y634383D01*
Y633967D01*
X1251150Y633758D01*
G01X1263550Y646675D02*
X1262310Y646258D01*
X1261380Y645217D01*
X1260760Y643967D01*
X1260295Y642300D01*
X1260140Y640425D01*
X1260295Y638550D01*
X1260760Y636883D01*
X1261380Y635633D01*
X1262310Y634592D01*
X1263550Y634175D01*
X1264790Y634592D01*
X1265720Y635633D01*
X1266340Y636883D01*
X1266805Y638550D01*
X1266960Y640425D01*
X1266805Y642300D01*
X1266340Y643967D01*
X1265720Y645217D01*
X1264790Y646258D01*
X1263550Y646675D01*
G01X1228210Y605825D02*
Y618325D01*
X1222475Y609367D01*
X1230225D01*
G01X1238750Y618325D02*
X1237510Y617908D01*
X1236580Y616867D01*
X1235960Y615617D01*
X1235495Y613950D01*
X1235340Y612075D01*
X1235495Y610200D01*
X1235960Y608533D01*
X1236580Y607283D01*
X1237510Y606242D01*
X1238750Y605825D01*
X1239990Y606242D01*
X1240920Y607283D01*
X1241540Y608533D01*
X1242005Y610200D01*
X1242160Y612075D01*
X1242005Y613950D01*
X1241540Y615617D01*
X1240920Y616867D01*
X1239990Y617908D01*
X1238750Y618325D01*
G01X1251150Y605408D02*
X1250840Y605617D01*
Y606033D01*
X1251150Y606242D01*
X1251460Y606033D01*
Y605617D01*
X1251150Y605408D01*
G01X1263550Y618325D02*
X1262310Y617908D01*
X1261380Y616867D01*
X1260760Y615617D01*
X1260295Y613950D01*
X1260140Y612075D01*
X1260295Y610200D01*
X1260760Y608533D01*
X1261380Y607283D01*
X1262310Y606242D01*
X1263550Y605825D01*
X1264790Y606242D01*
X1265720Y607283D01*
X1266340Y608533D01*
X1266805Y610200D01*
X1266960Y612075D01*
X1266805Y613950D01*
X1266340Y615617D01*
X1265720Y616867D01*
X1264790Y617908D01*
X1263550Y618325D01*
G01X1226350Y690875D02*
Y703375D01*
X1224490Y700875D01*
G01Y690875D02*
X1228210D01*
G01X1235805Y696083D02*
X1236890Y697542D01*
X1237820Y698375D01*
X1239060Y698792D01*
X1240145Y698375D01*
X1240920Y697542D01*
X1241540Y696292D01*
X1241695Y694833D01*
X1241540Y693583D01*
X1240920Y692333D01*
X1239990Y691292D01*
X1238905Y690875D01*
X1237665Y691292D01*
X1236580Y692541D01*
X1235960Y694417D01*
X1235805Y696500D01*
X1236115Y699208D01*
X1236580Y700667D01*
X1237355Y702125D01*
X1238440Y703167D01*
X1239525Y703375D01*
X1240610Y702958D01*
X1241385Y701917D01*
G01X1251150Y690458D02*
X1250840Y690667D01*
Y691083D01*
X1251150Y691292D01*
X1251460Y691083D01*
Y690667D01*
X1251150Y690458D01*
G01X1263550Y703375D02*
X1262310Y702958D01*
X1261380Y701917D01*
X1260760Y700667D01*
X1260295Y699000D01*
X1260140Y697125D01*
X1260295Y695250D01*
X1260760Y693583D01*
X1261380Y692333D01*
X1262310Y691292D01*
X1263550Y690875D01*
X1264790Y691292D01*
X1265720Y692333D01*
X1266340Y693583D01*
X1266805Y695250D01*
X1266960Y697125D01*
X1266805Y699000D01*
X1266340Y700667D01*
X1265720Y701917D01*
X1264790Y702958D01*
X1263550Y703375D01*
G01X1223405Y672942D02*
X1224335Y674191D01*
X1225420Y674817D01*
X1226660Y675025D01*
X1228210Y674608D01*
X1229295Y673567D01*
X1229605Y672317D01*
X1229450Y671066D01*
X1228830Y670025D01*
X1225730Y667942D01*
X1224335Y666483D01*
X1223405Y664400D01*
X1223095Y662525D01*
X1229605D01*
G01X1238750D02*
X1239835Y662733D01*
X1241075Y663358D01*
X1241850Y664400D01*
X1242160Y665858D01*
X1241850Y667316D01*
X1240920Y668567D01*
X1239525Y669192D01*
X1237975D01*
X1237045Y669608D01*
X1236270Y670650D01*
X1235960Y672108D01*
X1236425Y673567D01*
X1237510Y674608D01*
X1238750Y675025D01*
X1239990Y674608D01*
X1241075Y673567D01*
X1241540Y672108D01*
X1241230Y670650D01*
X1240455Y669608D01*
X1239525Y669192D01*
X1237975D01*
X1236580Y668567D01*
X1235650Y667316D01*
X1235340Y665858D01*
X1235650Y664400D01*
X1236425Y663358D01*
X1237665Y662733D01*
X1238750Y662525D01*
G01X1251150Y662108D02*
X1250840Y662317D01*
Y662733D01*
X1251150Y662942D01*
X1251460Y662733D01*
Y662317D01*
X1251150Y662108D01*
G01X1263550Y675025D02*
X1262310Y674608D01*
X1261380Y673567D01*
X1260760Y672317D01*
X1260295Y670650D01*
X1260140Y668775D01*
X1260295Y666900D01*
X1260760Y665233D01*
X1261380Y663983D01*
X1262310Y662942D01*
X1263550Y662525D01*
X1264790Y662942D01*
X1265720Y663983D01*
X1266340Y665233D01*
X1266805Y666900D01*
X1266960Y668775D01*
X1266805Y670650D01*
X1266340Y672317D01*
X1265720Y673567D01*
X1264790Y674608D01*
X1263550Y675025D01*
G01X1226350Y775925D02*
Y788425D01*
X1224490Y785925D01*
G01Y775925D02*
X1228210D01*
G01X1235805Y786342D02*
X1236735Y787591D01*
X1237820Y788217D01*
X1239060Y788425D01*
X1240610Y788008D01*
X1241695Y786967D01*
X1242005Y785717D01*
X1241850Y784466D01*
X1241230Y783425D01*
X1238130Y781342D01*
X1236735Y779883D01*
X1235805Y777800D01*
X1235495Y775925D01*
X1242005D01*
G01X1251150Y775508D02*
X1250840Y775717D01*
Y776133D01*
X1251150Y776342D01*
X1251460Y776133D01*
Y775717D01*
X1251150Y775508D01*
G01X1263550Y788425D02*
X1262310Y788008D01*
X1261380Y786967D01*
X1260760Y785717D01*
X1260295Y784050D01*
X1260140Y782175D01*
X1260295Y780300D01*
X1260760Y778633D01*
X1261380Y777383D01*
X1262310Y776342D01*
X1263550Y775925D01*
X1264790Y776342D01*
X1265720Y777383D01*
X1266340Y778633D01*
X1266805Y780300D01*
X1266960Y782175D01*
X1266805Y784050D01*
X1266340Y785717D01*
X1265720Y786967D01*
X1264790Y788008D01*
X1263550Y788425D01*
G01X1226350Y747575D02*
Y760075D01*
X1224490Y757575D01*
G01Y747575D02*
X1228210D01*
G01X1240610D02*
Y760075D01*
X1234875Y751117D01*
X1242625D01*
G01X1251150Y747158D02*
X1250840Y747367D01*
Y747783D01*
X1251150Y747992D01*
X1251460Y747783D01*
Y747367D01*
X1251150Y747158D01*
G01X1263550Y760075D02*
X1262310Y759658D01*
X1261380Y758617D01*
X1260760Y757367D01*
X1260295Y755700D01*
X1260140Y753825D01*
X1260295Y751950D01*
X1260760Y750283D01*
X1261380Y749033D01*
X1262310Y747992D01*
X1263550Y747575D01*
X1264790Y747992D01*
X1265720Y749033D01*
X1266340Y750283D01*
X1266805Y751950D01*
X1266960Y753825D01*
X1266805Y755700D01*
X1266340Y757367D01*
X1265720Y758617D01*
X1264790Y759658D01*
X1263550Y760075D01*
G01X1226350Y832625D02*
Y845125D01*
X1224490Y842625D01*
G01Y832625D02*
X1228210D01*
G01X1238750Y845125D02*
X1237510Y844708D01*
X1236580Y843667D01*
X1235960Y842417D01*
X1235495Y840750D01*
X1235340Y838875D01*
X1235495Y837000D01*
X1235960Y835333D01*
X1236580Y834083D01*
X1237510Y833042D01*
X1238750Y832625D01*
X1239990Y833042D01*
X1240920Y834083D01*
X1241540Y835333D01*
X1242005Y837000D01*
X1242160Y838875D01*
X1242005Y840750D01*
X1241540Y842417D01*
X1240920Y843667D01*
X1239990Y844708D01*
X1238750Y845125D01*
G01X1251150Y832208D02*
X1250840Y832417D01*
Y832833D01*
X1251150Y833042D01*
X1251460Y832833D01*
Y832417D01*
X1251150Y832208D01*
G01X1263550Y845125D02*
X1262310Y844708D01*
X1261380Y843667D01*
X1260760Y842417D01*
X1260295Y840750D01*
X1260140Y838875D01*
X1260295Y837000D01*
X1260760Y835333D01*
X1261380Y834083D01*
X1262310Y833042D01*
X1263550Y832625D01*
X1264790Y833042D01*
X1265720Y834083D01*
X1266340Y835333D01*
X1266805Y837000D01*
X1266960Y838875D01*
X1266805Y840750D01*
X1266340Y842417D01*
X1265720Y843667D01*
X1264790Y844708D01*
X1263550Y845125D01*
G01X1226350Y804275D02*
Y816775D01*
X1224490Y814275D01*
G01Y804275D02*
X1228210D01*
G01X1238750Y816775D02*
X1237510Y816358D01*
X1236580Y815317D01*
X1235960Y814067D01*
X1235495Y812400D01*
X1235340Y810525D01*
X1235495Y808650D01*
X1235960Y806983D01*
X1236580Y805733D01*
X1237510Y804692D01*
X1238750Y804275D01*
X1239990Y804692D01*
X1240920Y805733D01*
X1241540Y806983D01*
X1242005Y808650D01*
X1242160Y810525D01*
X1242005Y812400D01*
X1241540Y814067D01*
X1240920Y815317D01*
X1239990Y816358D01*
X1238750Y816775D01*
G01X1251150Y803858D02*
X1250840Y804067D01*
Y804483D01*
X1251150Y804692D01*
X1251460Y804483D01*
Y804067D01*
X1251150Y803858D01*
G01X1263550Y816775D02*
X1262310Y816358D01*
X1261380Y815317D01*
X1260760Y814067D01*
X1260295Y812400D01*
X1260140Y810525D01*
X1260295Y808650D01*
X1260760Y806983D01*
X1261380Y805733D01*
X1262310Y804692D01*
X1263550Y804275D01*
X1264790Y804692D01*
X1265720Y805733D01*
X1266340Y806983D01*
X1266805Y808650D01*
X1266960Y810525D01*
X1266805Y812400D01*
X1266340Y814067D01*
X1265720Y815317D01*
X1264790Y816358D01*
X1263550Y816775D01*
G01X1223095Y892416D02*
X1224335Y891375D01*
X1225730Y890750D01*
X1226970D01*
X1228210Y891375D01*
X1229140Y892416D01*
X1229605Y893875D01*
X1229295Y895333D01*
X1228520Y896583D01*
X1227125Y897417D01*
X1225265Y897833D01*
X1224180Y898667D01*
X1223715Y900125D01*
X1224025Y901583D01*
X1224800Y902625D01*
X1225885Y903250D01*
X1226970D01*
X1228055Y902833D01*
X1228985Y901792D01*
G01X1236890Y903250D02*
X1240610D01*
G01X1238750D02*
Y890750D01*
G01X1236890D02*
X1240610D01*
G01X1248205Y903250D02*
X1254095D01*
X1248205Y890750D01*
X1254095D01*
G01X1266650D02*
X1260450D01*
Y903250D01*
X1266650D01*
G01X1264170Y897208D02*
X1260450D01*
G01X1232550Y860975D02*
X1233635Y861183D01*
X1234875Y861808D01*
X1235650Y862850D01*
X1235960Y864308D01*
X1235650Y865766D01*
X1234720Y867017D01*
X1233325Y867642D01*
X1231775D01*
X1230845Y868058D01*
X1230070Y869100D01*
X1229760Y870558D01*
X1230225Y872017D01*
X1231310Y873058D01*
X1232550Y873475D01*
X1233790Y873058D01*
X1234875Y872017D01*
X1235340Y870558D01*
X1235030Y869100D01*
X1234255Y868058D01*
X1233325Y867642D01*
X1231775D01*
X1230380Y867017D01*
X1229450Y865766D01*
X1229140Y864308D01*
X1229450Y862850D01*
X1230225Y861808D01*
X1231465Y861183D01*
X1232550Y860975D01*
G01X1244950Y860558D02*
X1244640Y860767D01*
Y861183D01*
X1244950Y861392D01*
X1245260Y861183D01*
Y860767D01*
X1244950Y860558D01*
G01X1257350Y873475D02*
X1256110Y873058D01*
X1255180Y872017D01*
X1254560Y870767D01*
X1254095Y869100D01*
X1253940Y867225D01*
X1254095Y865350D01*
X1254560Y863683D01*
X1255180Y862433D01*
X1256110Y861392D01*
X1257350Y860975D01*
X1258590Y861392D01*
X1259520Y862433D01*
X1260140Y863683D01*
X1260605Y865350D01*
X1260760Y867225D01*
X1260605Y869100D01*
X1260140Y870767D01*
X1259520Y872017D01*
X1258590Y873058D01*
X1257350Y873475D01*
G01X1343685Y180575D02*
Y193075D01*
X1350815Y180575D01*
Y193075D01*
G01X1359650Y180575D02*
X1358410Y180783D01*
X1357325Y181616D01*
X1356395Y182867D01*
X1355775Y184325D01*
X1355465Y185992D01*
Y187658D01*
X1355775Y189325D01*
X1356395Y190783D01*
X1357325Y192033D01*
X1358410Y192867D01*
X1359650Y193075D01*
X1360890Y192867D01*
X1361975Y192033D01*
X1362905Y190783D01*
X1363525Y189325D01*
X1363835Y187658D01*
Y185992D01*
X1363525Y184325D01*
X1362905Y182867D01*
X1361975Y181616D01*
X1360890Y180783D01*
X1359650Y180575D01*
G01X1368485D02*
Y193075D01*
X1375615Y180575D01*
Y193075D01*
G01X1382435Y184742D02*
X1386465D01*
G01X1393750Y180575D02*
Y193075D01*
X1397470D01*
X1398710Y192450D01*
X1399640Y190992D01*
X1399950Y189325D01*
X1399640Y187658D01*
X1398865Y186408D01*
X1397470Y185783D01*
X1393750D01*
G01X1406150Y193075D02*
Y180575D01*
X1412350D01*
G01X1417775D02*
X1421650Y193075D01*
X1425525Y180575D01*
G01X1424130Y184950D02*
X1419170D01*
G01X1434050Y193075D02*
Y180575D01*
G01X1430485Y193075D02*
X1437615D01*
G01X1449550Y180575D02*
X1443350D01*
Y193075D01*
X1449550D01*
G01X1447070Y187033D02*
X1443350D01*
G01X1455440Y180575D02*
Y193075D01*
X1458540D01*
X1459780Y192450D01*
X1460710Y191617D01*
X1461485Y190367D01*
X1462105Y188908D01*
X1462260Y186825D01*
X1462105Y184742D01*
X1461485Y183283D01*
X1460710Y182033D01*
X1459780Y181200D01*
X1458540Y180575D01*
X1455440D01*
G01X1343685Y152225D02*
Y164725D01*
X1350815Y152225D01*
Y164725D01*
G01X1359650Y152225D02*
X1358410Y152433D01*
X1357325Y153266D01*
X1356395Y154517D01*
X1355775Y155975D01*
X1355465Y157642D01*
Y159308D01*
X1355775Y160975D01*
X1356395Y162433D01*
X1357325Y163683D01*
X1358410Y164517D01*
X1359650Y164725D01*
X1360890Y164517D01*
X1361975Y163683D01*
X1362905Y162433D01*
X1363525Y160975D01*
X1363835Y159308D01*
Y157642D01*
X1363525Y155975D01*
X1362905Y154517D01*
X1361975Y153266D01*
X1360890Y152433D01*
X1359650Y152225D01*
G01X1368485D02*
Y164725D01*
X1375615Y152225D01*
Y164725D01*
G01X1382435Y156392D02*
X1386465D01*
G01X1393750Y152225D02*
Y164725D01*
X1397470D01*
X1398710Y164100D01*
X1399640Y162642D01*
X1399950Y160975D01*
X1399640Y159308D01*
X1398865Y158058D01*
X1397470Y157433D01*
X1393750D01*
G01X1406150Y164725D02*
Y152225D01*
X1412350D01*
G01X1417775D02*
X1421650Y164725D01*
X1425525Y152225D01*
G01X1424130Y156600D02*
X1419170D01*
G01X1434050Y164725D02*
Y152225D01*
G01X1430485Y164725D02*
X1437615D01*
G01X1449550Y152225D02*
X1443350D01*
Y164725D01*
X1449550D01*
G01X1447070Y158683D02*
X1443350D01*
G01X1455440Y152225D02*
Y164725D01*
X1458540D01*
X1459780Y164100D01*
X1460710Y163267D01*
X1461485Y162017D01*
X1462105Y160558D01*
X1462260Y158475D01*
X1462105Y156392D01*
X1461485Y154933D01*
X1460710Y153683D01*
X1459780Y152850D01*
X1458540Y152225D01*
X1455440D01*
G01X1339500Y909500D02*
Y144300D01*
G01X1343685Y265625D02*
Y278125D01*
X1350815Y265625D01*
Y278125D01*
G01X1359650Y265625D02*
X1358410Y265833D01*
X1357325Y266666D01*
X1356395Y267917D01*
X1355775Y269375D01*
X1355465Y271042D01*
Y272708D01*
X1355775Y274375D01*
X1356395Y275833D01*
X1357325Y277083D01*
X1358410Y277917D01*
X1359650Y278125D01*
X1360890Y277917D01*
X1361975Y277083D01*
X1362905Y275833D01*
X1363525Y274375D01*
X1363835Y272708D01*
Y271042D01*
X1363525Y269375D01*
X1362905Y267917D01*
X1361975Y266666D01*
X1360890Y265833D01*
X1359650Y265625D01*
G01X1368485D02*
Y278125D01*
X1375615Y265625D01*
Y278125D01*
G01X1382435Y269792D02*
X1386465D01*
G01X1393750Y265625D02*
Y278125D01*
X1397470D01*
X1398710Y277500D01*
X1399640Y276042D01*
X1399950Y274375D01*
X1399640Y272708D01*
X1398865Y271458D01*
X1397470Y270833D01*
X1393750D01*
G01X1406150Y278125D02*
Y265625D01*
X1412350D01*
G01X1417775D02*
X1421650Y278125D01*
X1425525Y265625D01*
G01X1424130Y270000D02*
X1419170D01*
G01X1434050Y278125D02*
Y265625D01*
G01X1430485Y278125D02*
X1437615D01*
G01X1449550Y265625D02*
X1443350D01*
Y278125D01*
X1449550D01*
G01X1447070Y272083D02*
X1443350D01*
G01X1455440Y265625D02*
Y278125D01*
X1458540D01*
X1459780Y277500D01*
X1460710Y276667D01*
X1461485Y275417D01*
X1462105Y273958D01*
X1462260Y271875D01*
X1462105Y269792D01*
X1461485Y268333D01*
X1460710Y267083D01*
X1459780Y266250D01*
X1458540Y265625D01*
X1455440D01*
G01X1343685Y350675D02*
Y363175D01*
X1350815Y350675D01*
Y363175D01*
G01X1359650Y350675D02*
X1358410Y350883D01*
X1357325Y351716D01*
X1356395Y352967D01*
X1355775Y354425D01*
X1355465Y356092D01*
Y357758D01*
X1355775Y359425D01*
X1356395Y360883D01*
X1357325Y362133D01*
X1358410Y362967D01*
X1359650Y363175D01*
X1360890Y362967D01*
X1361975Y362133D01*
X1362905Y360883D01*
X1363525Y359425D01*
X1363835Y357758D01*
Y356092D01*
X1363525Y354425D01*
X1362905Y352967D01*
X1361975Y351716D01*
X1360890Y350883D01*
X1359650Y350675D01*
G01X1368485D02*
Y363175D01*
X1375615Y350675D01*
Y363175D01*
G01X1382435Y354842D02*
X1386465D01*
G01X1393750Y350675D02*
Y363175D01*
X1397470D01*
X1398710Y362550D01*
X1399640Y361092D01*
X1399950Y359425D01*
X1399640Y357758D01*
X1398865Y356508D01*
X1397470Y355883D01*
X1393750D01*
G01X1406150Y363175D02*
Y350675D01*
X1412350D01*
G01X1417775D02*
X1421650Y363175D01*
X1425525Y350675D01*
G01X1424130Y355050D02*
X1419170D01*
G01X1434050Y363175D02*
Y350675D01*
G01X1430485Y363175D02*
X1437615D01*
G01X1449550Y350675D02*
X1443350D01*
Y363175D01*
X1449550D01*
G01X1447070Y357133D02*
X1443350D01*
G01X1455440Y350675D02*
Y363175D01*
X1458540D01*
X1459780Y362550D01*
X1460710Y361717D01*
X1461485Y360467D01*
X1462105Y359008D01*
X1462260Y356925D01*
X1462105Y354842D01*
X1461485Y353383D01*
X1460710Y352133D01*
X1459780Y351300D01*
X1458540Y350675D01*
X1455440D01*
G01X1343685Y322325D02*
Y334825D01*
X1350815Y322325D01*
Y334825D01*
G01X1359650Y322325D02*
X1358410Y322533D01*
X1357325Y323366D01*
X1356395Y324617D01*
X1355775Y326075D01*
X1355465Y327742D01*
Y329408D01*
X1355775Y331075D01*
X1356395Y332533D01*
X1357325Y333783D01*
X1358410Y334617D01*
X1359650Y334825D01*
X1360890Y334617D01*
X1361975Y333783D01*
X1362905Y332533D01*
X1363525Y331075D01*
X1363835Y329408D01*
Y327742D01*
X1363525Y326075D01*
X1362905Y324617D01*
X1361975Y323366D01*
X1360890Y322533D01*
X1359650Y322325D01*
G01X1368485D02*
Y334825D01*
X1375615Y322325D01*
Y334825D01*
G01X1382435Y326492D02*
X1386465D01*
G01X1393750Y322325D02*
Y334825D01*
X1397470D01*
X1398710Y334200D01*
X1399640Y332742D01*
X1399950Y331075D01*
X1399640Y329408D01*
X1398865Y328158D01*
X1397470Y327533D01*
X1393750D01*
G01X1406150Y334825D02*
Y322325D01*
X1412350D01*
G01X1417775D02*
X1421650Y334825D01*
X1425525Y322325D01*
G01X1424130Y326700D02*
X1419170D01*
G01X1434050Y334825D02*
Y322325D01*
G01X1430485Y334825D02*
X1437615D01*
G01X1449550Y322325D02*
X1443350D01*
Y334825D01*
X1449550D01*
G01X1447070Y328783D02*
X1443350D01*
G01X1455440Y322325D02*
Y334825D01*
X1458540D01*
X1459780Y334200D01*
X1460710Y333367D01*
X1461485Y332117D01*
X1462105Y330658D01*
X1462260Y328575D01*
X1462105Y326492D01*
X1461485Y325033D01*
X1460710Y323783D01*
X1459780Y322950D01*
X1458540Y322325D01*
X1455440D01*
G01X1343685Y293975D02*
Y306475D01*
X1350815Y293975D01*
Y306475D01*
G01X1359650Y293975D02*
X1358410Y294183D01*
X1357325Y295016D01*
X1356395Y296267D01*
X1355775Y297725D01*
X1355465Y299392D01*
Y301058D01*
X1355775Y302725D01*
X1356395Y304183D01*
X1357325Y305433D01*
X1358410Y306267D01*
X1359650Y306475D01*
X1360890Y306267D01*
X1361975Y305433D01*
X1362905Y304183D01*
X1363525Y302725D01*
X1363835Y301058D01*
Y299392D01*
X1363525Y297725D01*
X1362905Y296267D01*
X1361975Y295016D01*
X1360890Y294183D01*
X1359650Y293975D01*
G01X1368485D02*
Y306475D01*
X1375615Y293975D01*
Y306475D01*
G01X1382435Y298142D02*
X1386465D01*
G01X1393750Y293975D02*
Y306475D01*
X1397470D01*
X1398710Y305850D01*
X1399640Y304392D01*
X1399950Y302725D01*
X1399640Y301058D01*
X1398865Y299808D01*
X1397470Y299183D01*
X1393750D01*
G01X1406150Y306475D02*
Y293975D01*
X1412350D01*
G01X1417775D02*
X1421650Y306475D01*
X1425525Y293975D01*
G01X1424130Y298350D02*
X1419170D01*
G01X1434050Y306475D02*
Y293975D01*
G01X1430485Y306475D02*
X1437615D01*
G01X1449550Y293975D02*
X1443350D01*
Y306475D01*
X1449550D01*
G01X1447070Y300433D02*
X1443350D01*
G01X1455440Y293975D02*
Y306475D01*
X1458540D01*
X1459780Y305850D01*
X1460710Y305017D01*
X1461485Y303767D01*
X1462105Y302308D01*
X1462260Y300225D01*
X1462105Y298142D01*
X1461485Y296683D01*
X1460710Y295433D01*
X1459780Y294600D01*
X1458540Y293975D01*
X1455440D01*
G01X1343685Y407375D02*
Y419875D01*
X1350815Y407375D01*
Y419875D01*
G01X1359650Y407375D02*
X1358410Y407583D01*
X1357325Y408416D01*
X1356395Y409667D01*
X1355775Y411125D01*
X1355465Y412792D01*
Y414458D01*
X1355775Y416125D01*
X1356395Y417583D01*
X1357325Y418833D01*
X1358410Y419667D01*
X1359650Y419875D01*
X1360890Y419667D01*
X1361975Y418833D01*
X1362905Y417583D01*
X1363525Y416125D01*
X1363835Y414458D01*
Y412792D01*
X1363525Y411125D01*
X1362905Y409667D01*
X1361975Y408416D01*
X1360890Y407583D01*
X1359650Y407375D01*
G01X1368485D02*
Y419875D01*
X1375615Y407375D01*
Y419875D01*
G01X1382435Y411542D02*
X1386465D01*
G01X1393750Y407375D02*
Y419875D01*
X1397470D01*
X1398710Y419250D01*
X1399640Y417792D01*
X1399950Y416125D01*
X1399640Y414458D01*
X1398865Y413208D01*
X1397470Y412583D01*
X1393750D01*
G01X1406150Y419875D02*
Y407375D01*
X1412350D01*
G01X1417775D02*
X1421650Y419875D01*
X1425525Y407375D01*
G01X1424130Y411750D02*
X1419170D01*
G01X1434050Y419875D02*
Y407375D01*
G01X1430485Y419875D02*
X1437615D01*
G01X1449550Y407375D02*
X1443350D01*
Y419875D01*
X1449550D01*
G01X1447070Y413833D02*
X1443350D01*
G01X1455440Y407375D02*
Y419875D01*
X1458540D01*
X1459780Y419250D01*
X1460710Y418417D01*
X1461485Y417167D01*
X1462105Y415708D01*
X1462260Y413625D01*
X1462105Y411542D01*
X1461485Y410083D01*
X1460710Y408833D01*
X1459780Y408000D01*
X1458540Y407375D01*
X1455440D01*
G01X1343685Y379025D02*
Y391525D01*
X1350815Y379025D01*
Y391525D01*
G01X1359650Y379025D02*
X1358410Y379233D01*
X1357325Y380066D01*
X1356395Y381317D01*
X1355775Y382775D01*
X1355465Y384442D01*
Y386108D01*
X1355775Y387775D01*
X1356395Y389233D01*
X1357325Y390483D01*
X1358410Y391317D01*
X1359650Y391525D01*
X1360890Y391317D01*
X1361975Y390483D01*
X1362905Y389233D01*
X1363525Y387775D01*
X1363835Y386108D01*
Y384442D01*
X1363525Y382775D01*
X1362905Y381317D01*
X1361975Y380066D01*
X1360890Y379233D01*
X1359650Y379025D01*
G01X1368485D02*
Y391525D01*
X1375615Y379025D01*
Y391525D01*
G01X1382435Y383192D02*
X1386465D01*
G01X1393750Y379025D02*
Y391525D01*
X1397470D01*
X1398710Y390900D01*
X1399640Y389442D01*
X1399950Y387775D01*
X1399640Y386108D01*
X1398865Y384858D01*
X1397470Y384233D01*
X1393750D01*
G01X1406150Y391525D02*
Y379025D01*
X1412350D01*
G01X1417775D02*
X1421650Y391525D01*
X1425525Y379025D01*
G01X1424130Y383400D02*
X1419170D01*
G01X1434050Y391525D02*
Y379025D01*
G01X1430485Y391525D02*
X1437615D01*
G01X1449550Y379025D02*
X1443350D01*
Y391525D01*
X1449550D01*
G01X1447070Y385483D02*
X1443350D01*
G01X1455440Y379025D02*
Y391525D01*
X1458540D01*
X1459780Y390900D01*
X1460710Y390067D01*
X1461485Y388817D01*
X1462105Y387358D01*
X1462260Y385275D01*
X1462105Y383192D01*
X1461485Y381733D01*
X1460710Y380483D01*
X1459780Y379650D01*
X1458540Y379025D01*
X1455440D01*
G01X1343685Y492425D02*
Y504925D01*
X1350815Y492425D01*
Y504925D01*
G01X1359650Y492425D02*
X1358410Y492633D01*
X1357325Y493466D01*
X1356395Y494717D01*
X1355775Y496175D01*
X1355465Y497842D01*
Y499508D01*
X1355775Y501175D01*
X1356395Y502633D01*
X1357325Y503883D01*
X1358410Y504717D01*
X1359650Y504925D01*
X1360890Y504717D01*
X1361975Y503883D01*
X1362905Y502633D01*
X1363525Y501175D01*
X1363835Y499508D01*
Y497842D01*
X1363525Y496175D01*
X1362905Y494717D01*
X1361975Y493466D01*
X1360890Y492633D01*
X1359650Y492425D01*
G01X1368485D02*
Y504925D01*
X1375615Y492425D01*
Y504925D01*
G01X1382435Y496592D02*
X1386465D01*
G01X1393750Y492425D02*
Y504925D01*
X1397470D01*
X1398710Y504300D01*
X1399640Y502842D01*
X1399950Y501175D01*
X1399640Y499508D01*
X1398865Y498258D01*
X1397470Y497633D01*
X1393750D01*
G01X1406150Y504925D02*
Y492425D01*
X1412350D01*
G01X1417775D02*
X1421650Y504925D01*
X1425525Y492425D01*
G01X1424130Y496800D02*
X1419170D01*
G01X1434050Y504925D02*
Y492425D01*
G01X1430485Y504925D02*
X1437615D01*
G01X1449550Y492425D02*
X1443350D01*
Y504925D01*
X1449550D01*
G01X1447070Y498883D02*
X1443350D01*
G01X1455440Y492425D02*
Y504925D01*
X1458540D01*
X1459780Y504300D01*
X1460710Y503467D01*
X1461485Y502217D01*
X1462105Y500758D01*
X1462260Y498675D01*
X1462105Y496592D01*
X1461485Y495133D01*
X1460710Y493883D01*
X1459780Y493050D01*
X1458540Y492425D01*
X1455440D01*
G01X1343685Y464075D02*
Y476575D01*
X1350815Y464075D01*
Y476575D01*
G01X1359650Y464075D02*
X1358410Y464283D01*
X1357325Y465116D01*
X1356395Y466367D01*
X1355775Y467825D01*
X1355465Y469492D01*
Y471158D01*
X1355775Y472825D01*
X1356395Y474283D01*
X1357325Y475533D01*
X1358410Y476367D01*
X1359650Y476575D01*
X1360890Y476367D01*
X1361975Y475533D01*
X1362905Y474283D01*
X1363525Y472825D01*
X1363835Y471158D01*
Y469492D01*
X1363525Y467825D01*
X1362905Y466367D01*
X1361975Y465116D01*
X1360890Y464283D01*
X1359650Y464075D01*
G01X1368485D02*
Y476575D01*
X1375615Y464075D01*
Y476575D01*
G01X1382435Y468242D02*
X1386465D01*
G01X1393750Y464075D02*
Y476575D01*
X1397470D01*
X1398710Y475950D01*
X1399640Y474492D01*
X1399950Y472825D01*
X1399640Y471158D01*
X1398865Y469908D01*
X1397470Y469283D01*
X1393750D01*
G01X1406150Y476575D02*
Y464075D01*
X1412350D01*
G01X1417775D02*
X1421650Y476575D01*
X1425525Y464075D01*
G01X1424130Y468450D02*
X1419170D01*
G01X1434050Y476575D02*
Y464075D01*
G01X1430485Y476575D02*
X1437615D01*
G01X1449550Y464075D02*
X1443350D01*
Y476575D01*
X1449550D01*
G01X1447070Y470533D02*
X1443350D01*
G01X1455440Y464075D02*
Y476575D01*
X1458540D01*
X1459780Y475950D01*
X1460710Y475117D01*
X1461485Y473867D01*
X1462105Y472408D01*
X1462260Y470325D01*
X1462105Y468242D01*
X1461485Y466783D01*
X1460710Y465533D01*
X1459780Y464700D01*
X1458540Y464075D01*
X1455440D01*
G01X1343685Y435725D02*
Y448225D01*
X1350815Y435725D01*
Y448225D01*
G01X1359650Y435725D02*
X1358410Y435933D01*
X1357325Y436766D01*
X1356395Y438017D01*
X1355775Y439475D01*
X1355465Y441142D01*
Y442808D01*
X1355775Y444475D01*
X1356395Y445933D01*
X1357325Y447183D01*
X1358410Y448017D01*
X1359650Y448225D01*
X1360890Y448017D01*
X1361975Y447183D01*
X1362905Y445933D01*
X1363525Y444475D01*
X1363835Y442808D01*
Y441142D01*
X1363525Y439475D01*
X1362905Y438017D01*
X1361975Y436766D01*
X1360890Y435933D01*
X1359650Y435725D01*
G01X1368485D02*
Y448225D01*
X1375615Y435725D01*
Y448225D01*
G01X1382435Y439892D02*
X1386465D01*
G01X1393750Y435725D02*
Y448225D01*
X1397470D01*
X1398710Y447600D01*
X1399640Y446142D01*
X1399950Y444475D01*
X1399640Y442808D01*
X1398865Y441558D01*
X1397470Y440933D01*
X1393750D01*
G01X1406150Y448225D02*
Y435725D01*
X1412350D01*
G01X1417775D02*
X1421650Y448225D01*
X1425525Y435725D01*
G01X1424130Y440100D02*
X1419170D01*
G01X1434050Y448225D02*
Y435725D01*
G01X1430485Y448225D02*
X1437615D01*
G01X1449550Y435725D02*
X1443350D01*
Y448225D01*
X1449550D01*
G01X1447070Y442183D02*
X1443350D01*
G01X1455440Y435725D02*
Y448225D01*
X1458540D01*
X1459780Y447600D01*
X1460710Y446767D01*
X1461485Y445517D01*
X1462105Y444058D01*
X1462260Y441975D01*
X1462105Y439892D01*
X1461485Y438433D01*
X1460710Y437183D01*
X1459780Y436350D01*
X1458540Y435725D01*
X1455440D01*
G01X1368950Y208925D02*
Y221425D01*
X1372670D01*
X1373910Y220800D01*
X1374840Y219342D01*
X1375150Y217675D01*
X1374840Y216008D01*
X1374065Y214758D01*
X1372670Y214133D01*
X1368950D01*
G01X1381350Y221425D02*
Y208925D01*
X1387550D01*
G01X1392975D02*
X1396850Y221425D01*
X1400725Y208925D01*
G01X1399330Y213300D02*
X1394370D01*
G01X1409250Y221425D02*
Y208925D01*
G01X1405685Y221425D02*
X1412815D01*
G01X1424750Y208925D02*
X1418550D01*
Y221425D01*
X1424750D01*
G01X1422270Y215383D02*
X1418550D01*
G01X1430640Y208925D02*
Y221425D01*
X1433740D01*
X1434980Y220800D01*
X1435910Y219967D01*
X1436685Y218717D01*
X1437305Y217258D01*
X1437460Y215175D01*
X1437305Y213092D01*
X1436685Y211633D01*
X1435910Y210383D01*
X1434980Y209550D01*
X1433740Y208925D01*
X1430640D01*
G01X1368950Y237275D02*
Y249775D01*
X1372670D01*
X1373910Y249150D01*
X1374840Y247692D01*
X1375150Y246025D01*
X1374840Y244358D01*
X1374065Y243108D01*
X1372670Y242483D01*
X1368950D01*
G01X1381350Y249775D02*
Y237275D01*
X1387550D01*
G01X1392975D02*
X1396850Y249775D01*
X1400725Y237275D01*
G01X1399330Y241650D02*
X1394370D01*
G01X1409250Y249775D02*
Y237275D01*
G01X1405685Y249775D02*
X1412815D01*
G01X1424750Y237275D02*
X1418550D01*
Y249775D01*
X1424750D01*
G01X1422270Y243733D02*
X1418550D01*
G01X1430640Y237275D02*
Y249775D01*
X1433740D01*
X1434980Y249150D01*
X1435910Y248317D01*
X1436685Y247067D01*
X1437305Y245608D01*
X1437460Y243525D01*
X1437305Y241442D01*
X1436685Y239983D01*
X1435910Y238733D01*
X1434980Y237900D01*
X1433740Y237275D01*
X1430640D01*
G01X1368950Y549125D02*
Y561625D01*
X1372670D01*
X1373910Y561000D01*
X1374840Y559542D01*
X1375150Y557875D01*
X1374840Y556208D01*
X1374065Y554958D01*
X1372670Y554333D01*
X1368950D01*
G01X1381350Y561625D02*
Y549125D01*
X1387550D01*
G01X1392975D02*
X1396850Y561625D01*
X1400725Y549125D01*
G01X1399330Y553500D02*
X1394370D01*
G01X1409250Y561625D02*
Y549125D01*
G01X1405685Y561625D02*
X1412815D01*
G01X1424750Y549125D02*
X1418550D01*
Y561625D01*
X1424750D01*
G01X1422270Y555583D02*
X1418550D01*
G01X1430640Y549125D02*
Y561625D01*
X1433740D01*
X1434980Y561000D01*
X1435910Y560167D01*
X1436685Y558917D01*
X1437305Y557458D01*
X1437460Y555375D01*
X1437305Y553292D01*
X1436685Y551833D01*
X1435910Y550583D01*
X1434980Y549750D01*
X1433740Y549125D01*
X1430640D01*
G01X1368950Y520775D02*
Y533275D01*
X1372670D01*
X1373910Y532650D01*
X1374840Y531192D01*
X1375150Y529525D01*
X1374840Y527858D01*
X1374065Y526608D01*
X1372670Y525983D01*
X1368950D01*
G01X1381350Y533275D02*
Y520775D01*
X1387550D01*
G01X1392975D02*
X1396850Y533275D01*
X1400725Y520775D01*
G01X1399330Y525150D02*
X1394370D01*
G01X1409250Y533275D02*
Y520775D01*
G01X1405685Y533275D02*
X1412815D01*
G01X1424750Y520775D02*
X1418550D01*
Y533275D01*
X1424750D01*
G01X1422270Y527233D02*
X1418550D01*
G01X1430640Y520775D02*
Y533275D01*
X1433740D01*
X1434980Y532650D01*
X1435910Y531817D01*
X1436685Y530567D01*
X1437305Y529108D01*
X1437460Y527025D01*
X1437305Y524942D01*
X1436685Y523483D01*
X1435910Y522233D01*
X1434980Y521400D01*
X1433740Y520775D01*
X1430640D01*
G01X1368950Y634175D02*
Y646675D01*
X1372670D01*
X1373910Y646050D01*
X1374840Y644592D01*
X1375150Y642925D01*
X1374840Y641258D01*
X1374065Y640008D01*
X1372670Y639383D01*
X1368950D01*
G01X1381350Y646675D02*
Y634175D01*
X1387550D01*
G01X1392975D02*
X1396850Y646675D01*
X1400725Y634175D01*
G01X1399330Y638550D02*
X1394370D01*
G01X1409250Y646675D02*
Y634175D01*
G01X1405685Y646675D02*
X1412815D01*
G01X1424750Y634175D02*
X1418550D01*
Y646675D01*
X1424750D01*
G01X1422270Y640633D02*
X1418550D01*
G01X1430640Y634175D02*
Y646675D01*
X1433740D01*
X1434980Y646050D01*
X1435910Y645217D01*
X1436685Y643967D01*
X1437305Y642508D01*
X1437460Y640425D01*
X1437305Y638342D01*
X1436685Y636883D01*
X1435910Y635633D01*
X1434980Y634800D01*
X1433740Y634175D01*
X1430640D01*
G01X1368950Y605825D02*
Y618325D01*
X1372670D01*
X1373910Y617700D01*
X1374840Y616242D01*
X1375150Y614575D01*
X1374840Y612908D01*
X1374065Y611658D01*
X1372670Y611033D01*
X1368950D01*
G01X1381350Y618325D02*
Y605825D01*
X1387550D01*
G01X1392975D02*
X1396850Y618325D01*
X1400725Y605825D01*
G01X1399330Y610200D02*
X1394370D01*
G01X1409250Y618325D02*
Y605825D01*
G01X1405685Y618325D02*
X1412815D01*
G01X1424750Y605825D02*
X1418550D01*
Y618325D01*
X1424750D01*
G01X1422270Y612283D02*
X1418550D01*
G01X1430640Y605825D02*
Y618325D01*
X1433740D01*
X1434980Y617700D01*
X1435910Y616867D01*
X1436685Y615617D01*
X1437305Y614158D01*
X1437460Y612075D01*
X1437305Y609992D01*
X1436685Y608533D01*
X1435910Y607283D01*
X1434980Y606450D01*
X1433740Y605825D01*
X1430640D01*
G01X1368950Y577475D02*
Y589975D01*
X1372670D01*
X1373910Y589350D01*
X1374840Y587892D01*
X1375150Y586225D01*
X1374840Y584558D01*
X1374065Y583308D01*
X1372670Y582683D01*
X1368950D01*
G01X1381350Y589975D02*
Y577475D01*
X1387550D01*
G01X1392975D02*
X1396850Y589975D01*
X1400725Y577475D01*
G01X1399330Y581850D02*
X1394370D01*
G01X1409250Y589975D02*
Y577475D01*
G01X1405685Y589975D02*
X1412815D01*
G01X1424750Y577475D02*
X1418550D01*
Y589975D01*
X1424750D01*
G01X1422270Y583933D02*
X1418550D01*
G01X1430640Y577475D02*
Y589975D01*
X1433740D01*
X1434980Y589350D01*
X1435910Y588517D01*
X1436685Y587267D01*
X1437305Y585808D01*
X1437460Y583725D01*
X1437305Y581642D01*
X1436685Y580183D01*
X1435910Y578933D01*
X1434980Y578100D01*
X1433740Y577475D01*
X1430640D01*
G01X1368950Y690875D02*
Y703375D01*
X1372670D01*
X1373910Y702750D01*
X1374840Y701292D01*
X1375150Y699625D01*
X1374840Y697958D01*
X1374065Y696708D01*
X1372670Y696083D01*
X1368950D01*
G01X1381350Y703375D02*
Y690875D01*
X1387550D01*
G01X1392975D02*
X1396850Y703375D01*
X1400725Y690875D01*
G01X1399330Y695250D02*
X1394370D01*
G01X1409250Y703375D02*
Y690875D01*
G01X1405685Y703375D02*
X1412815D01*
G01X1424750Y690875D02*
X1418550D01*
Y703375D01*
X1424750D01*
G01X1422270Y697333D02*
X1418550D01*
G01X1430640Y690875D02*
Y703375D01*
X1433740D01*
X1434980Y702750D01*
X1435910Y701917D01*
X1436685Y700667D01*
X1437305Y699208D01*
X1437460Y697125D01*
X1437305Y695042D01*
X1436685Y693583D01*
X1435910Y692333D01*
X1434980Y691500D01*
X1433740Y690875D01*
X1430640D01*
G01X1368950Y662525D02*
Y675025D01*
X1372670D01*
X1373910Y674400D01*
X1374840Y672942D01*
X1375150Y671275D01*
X1374840Y669608D01*
X1374065Y668358D01*
X1372670Y667733D01*
X1368950D01*
G01X1381350Y675025D02*
Y662525D01*
X1387550D01*
G01X1392975D02*
X1396850Y675025D01*
X1400725Y662525D01*
G01X1399330Y666900D02*
X1394370D01*
G01X1409250Y675025D02*
Y662525D01*
G01X1405685Y675025D02*
X1412815D01*
G01X1424750Y662525D02*
X1418550D01*
Y675025D01*
X1424750D01*
G01X1422270Y668983D02*
X1418550D01*
G01X1430640Y662525D02*
Y675025D01*
X1433740D01*
X1434980Y674400D01*
X1435910Y673567D01*
X1436685Y672317D01*
X1437305Y670858D01*
X1437460Y668775D01*
X1437305Y666692D01*
X1436685Y665233D01*
X1435910Y663983D01*
X1434980Y663150D01*
X1433740Y662525D01*
X1430640D01*
G01X1368950Y775925D02*
Y788425D01*
X1372670D01*
X1373910Y787800D01*
X1374840Y786342D01*
X1375150Y784675D01*
X1374840Y783008D01*
X1374065Y781758D01*
X1372670Y781133D01*
X1368950D01*
G01X1381350Y788425D02*
Y775925D01*
X1387550D01*
G01X1392975D02*
X1396850Y788425D01*
X1400725Y775925D01*
G01X1399330Y780300D02*
X1394370D01*
G01X1409250Y788425D02*
Y775925D01*
G01X1405685Y788425D02*
X1412815D01*
G01X1424750Y775925D02*
X1418550D01*
Y788425D01*
X1424750D01*
G01X1422270Y782383D02*
X1418550D01*
G01X1430640Y775925D02*
Y788425D01*
X1433740D01*
X1434980Y787800D01*
X1435910Y786967D01*
X1436685Y785717D01*
X1437305Y784258D01*
X1437460Y782175D01*
X1437305Y780092D01*
X1436685Y778633D01*
X1435910Y777383D01*
X1434980Y776550D01*
X1433740Y775925D01*
X1430640D01*
G01X1368950Y747575D02*
Y760075D01*
X1372670D01*
X1373910Y759450D01*
X1374840Y757992D01*
X1375150Y756325D01*
X1374840Y754658D01*
X1374065Y753408D01*
X1372670Y752783D01*
X1368950D01*
G01X1381350Y760075D02*
Y747575D01*
X1387550D01*
G01X1392975D02*
X1396850Y760075D01*
X1400725Y747575D01*
G01X1399330Y751950D02*
X1394370D01*
G01X1409250Y760075D02*
Y747575D01*
G01X1405685Y760075D02*
X1412815D01*
G01X1424750Y747575D02*
X1418550D01*
Y760075D01*
X1424750D01*
G01X1422270Y754033D02*
X1418550D01*
G01X1430640Y747575D02*
Y760075D01*
X1433740D01*
X1434980Y759450D01*
X1435910Y758617D01*
X1436685Y757367D01*
X1437305Y755908D01*
X1437460Y753825D01*
X1437305Y751742D01*
X1436685Y750283D01*
X1435910Y749033D01*
X1434980Y748200D01*
X1433740Y747575D01*
X1430640D01*
G01X1368950Y719225D02*
Y731725D01*
X1372670D01*
X1373910Y731100D01*
X1374840Y729642D01*
X1375150Y727975D01*
X1374840Y726308D01*
X1374065Y725058D01*
X1372670Y724433D01*
X1368950D01*
G01X1381350Y731725D02*
Y719225D01*
X1387550D01*
G01X1392975D02*
X1396850Y731725D01*
X1400725Y719225D01*
G01X1399330Y723600D02*
X1394370D01*
G01X1409250Y731725D02*
Y719225D01*
G01X1405685Y731725D02*
X1412815D01*
G01X1424750Y719225D02*
X1418550D01*
Y731725D01*
X1424750D01*
G01X1422270Y725683D02*
X1418550D01*
G01X1430640Y719225D02*
Y731725D01*
X1433740D01*
X1434980Y731100D01*
X1435910Y730267D01*
X1436685Y729017D01*
X1437305Y727558D01*
X1437460Y725475D01*
X1437305Y723392D01*
X1436685Y721933D01*
X1435910Y720683D01*
X1434980Y719850D01*
X1433740Y719225D01*
X1430640D01*
G01X1368950Y832625D02*
Y845125D01*
X1372670D01*
X1373910Y844500D01*
X1374840Y843042D01*
X1375150Y841375D01*
X1374840Y839708D01*
X1374065Y838458D01*
X1372670Y837833D01*
X1368950D01*
G01X1381350Y845125D02*
Y832625D01*
X1387550D01*
G01X1392975D02*
X1396850Y845125D01*
X1400725Y832625D01*
G01X1399330Y837000D02*
X1394370D01*
G01X1409250Y845125D02*
Y832625D01*
G01X1405685Y845125D02*
X1412815D01*
G01X1424750Y832625D02*
X1418550D01*
Y845125D01*
X1424750D01*
G01X1422270Y839083D02*
X1418550D01*
G01X1430640Y832625D02*
Y845125D01*
X1433740D01*
X1434980Y844500D01*
X1435910Y843667D01*
X1436685Y842417D01*
X1437305Y840958D01*
X1437460Y838875D01*
X1437305Y836792D01*
X1436685Y835333D01*
X1435910Y834083D01*
X1434980Y833250D01*
X1433740Y832625D01*
X1430640D01*
G01X1368950Y804275D02*
Y816775D01*
X1372670D01*
X1373910Y816150D01*
X1374840Y814692D01*
X1375150Y813025D01*
X1374840Y811358D01*
X1374065Y810108D01*
X1372670Y809483D01*
X1368950D01*
G01X1381350Y816775D02*
Y804275D01*
X1387550D01*
G01X1392975D02*
X1396850Y816775D01*
X1400725Y804275D01*
G01X1399330Y808650D02*
X1394370D01*
G01X1409250Y816775D02*
Y804275D01*
G01X1405685Y816775D02*
X1412815D01*
G01X1424750Y804275D02*
X1418550D01*
Y816775D01*
X1424750D01*
G01X1422270Y810733D02*
X1418550D01*
G01X1430640Y804275D02*
Y816775D01*
X1433740D01*
X1434980Y816150D01*
X1435910Y815317D01*
X1436685Y814067D01*
X1437305Y812608D01*
X1437460Y810525D01*
X1437305Y808442D01*
X1436685Y806983D01*
X1435910Y805733D01*
X1434980Y804900D01*
X1433740Y804275D01*
X1430640D01*
G01X1368950Y890750D02*
Y903250D01*
X1372670D01*
X1373910Y902625D01*
X1374840Y901167D01*
X1375150Y899500D01*
X1374840Y897833D01*
X1374065Y896583D01*
X1372670Y895958D01*
X1368950D01*
G01X1381350Y903250D02*
Y890750D01*
X1387550D01*
G01X1392975D02*
X1396850Y903250D01*
X1400725Y890750D01*
G01X1399330Y895125D02*
X1394370D01*
G01X1409250Y903250D02*
Y890750D01*
G01X1405685Y903250D02*
X1412815D01*
G01X1424750Y890750D02*
X1418550D01*
Y903250D01*
X1424750D01*
G01X1422270Y897208D02*
X1418550D01*
G01X1430640Y890750D02*
Y903250D01*
X1433740D01*
X1434980Y902625D01*
X1435910Y901792D01*
X1436685Y900542D01*
X1437305Y899083D01*
X1437460Y897000D01*
X1437305Y894917D01*
X1436685Y893458D01*
X1435910Y892208D01*
X1434980Y891375D01*
X1433740Y890750D01*
X1430640D01*
G01X1368950Y860975D02*
Y873475D01*
X1372670D01*
X1373910Y872850D01*
X1374840Y871392D01*
X1375150Y869725D01*
X1374840Y868058D01*
X1374065Y866808D01*
X1372670Y866183D01*
X1368950D01*
G01X1381350Y873475D02*
Y860975D01*
X1387550D01*
G01X1392975D02*
X1396850Y873475D01*
X1400725Y860975D01*
G01X1399330Y865350D02*
X1394370D01*
G01X1409250Y873475D02*
Y860975D01*
G01X1405685Y873475D02*
X1412815D01*
G01X1424750Y860975D02*
X1418550D01*
Y873475D01*
X1424750D01*
G01X1422270Y867433D02*
X1418550D01*
G01X1430640Y860975D02*
Y873475D01*
X1433740D01*
X1434980Y872850D01*
X1435910Y872017D01*
X1436685Y870767D01*
X1437305Y869308D01*
X1437460Y867225D01*
X1437305Y865142D01*
X1436685Y863683D01*
X1435910Y862433D01*
X1434980Y861600D01*
X1433740Y860975D01*
X1430640D01*
G01X1502405Y219342D02*
X1503335Y220591D01*
X1504420Y221217D01*
X1505660Y221425D01*
X1507210Y221008D01*
X1508295Y219967D01*
X1508605Y218717D01*
X1508450Y217466D01*
X1507830Y216425D01*
X1504730Y214342D01*
X1503335Y212883D01*
X1502405Y210800D01*
X1502095Y208925D01*
X1508605D01*
G01X1507210Y180575D02*
Y193075D01*
X1501475Y184117D01*
X1509225D01*
G01X1502405Y162642D02*
X1503335Y163891D01*
X1504420Y164517D01*
X1505660Y164725D01*
X1507210Y164308D01*
X1508295Y163267D01*
X1508605Y162017D01*
X1508450Y160766D01*
X1507830Y159725D01*
X1504730Y157642D01*
X1503335Y156183D01*
X1502405Y154100D01*
X1502095Y152225D01*
X1508605D01*
G01X1466600Y909500D02*
Y144300D01*
G01X1502405Y276042D02*
X1503335Y277291D01*
X1504420Y277917D01*
X1505660Y278125D01*
X1507210Y277708D01*
X1508295Y276667D01*
X1508605Y275417D01*
X1508450Y274166D01*
X1507830Y273125D01*
X1504730Y271042D01*
X1503335Y269583D01*
X1502405Y267500D01*
X1502095Y265625D01*
X1508605D01*
G01X1502405Y247692D02*
X1503335Y248941D01*
X1504420Y249567D01*
X1505660Y249775D01*
X1507210Y249358D01*
X1508295Y248317D01*
X1508605Y247067D01*
X1508450Y245816D01*
X1507830Y244775D01*
X1504730Y242692D01*
X1503335Y241233D01*
X1502405Y239150D01*
X1502095Y237275D01*
X1508605D01*
G01X1505040Y350675D02*
X1505350Y353383D01*
X1505815Y355675D01*
X1506435Y357758D01*
X1507210Y360050D01*
X1508450Y363175D01*
X1502250D01*
G01X1505350Y322325D02*
Y334825D01*
X1503490Y332325D01*
G01Y322325D02*
X1507210D01*
G01X1505350Y293975D02*
Y306475D01*
X1503490Y303975D01*
G01Y293975D02*
X1507210D01*
G01X1505350Y407375D02*
Y419875D01*
X1503490Y417375D01*
G01Y407375D02*
X1507210D01*
G01X1502405Y389442D02*
X1503335Y390691D01*
X1504420Y391317D01*
X1505660Y391525D01*
X1507210Y391108D01*
X1508295Y390067D01*
X1508605Y388817D01*
X1508450Y387566D01*
X1507830Y386525D01*
X1504730Y384442D01*
X1503335Y382983D01*
X1502405Y380900D01*
X1502095Y379025D01*
X1508605D01*
G01X1502405Y502842D02*
X1503335Y504091D01*
X1504420Y504717D01*
X1505660Y504925D01*
X1507210Y504508D01*
X1508295Y503467D01*
X1508605Y502217D01*
X1508450Y500966D01*
X1507830Y499925D01*
X1504730Y497842D01*
X1503335Y496383D01*
X1502405Y494300D01*
X1502095Y492425D01*
X1508605D01*
G01X1505350Y464075D02*
Y476575D01*
X1503490Y474075D01*
G01Y464075D02*
X1507210D01*
G01X1502405Y446142D02*
X1503335Y447391D01*
X1504420Y448017D01*
X1505660Y448225D01*
X1507210Y447808D01*
X1508295Y446767D01*
X1508605Y445517D01*
X1508450Y444266D01*
X1507830Y443225D01*
X1504730Y441142D01*
X1503335Y439683D01*
X1502405Y437600D01*
X1502095Y435725D01*
X1508605D01*
G01X1502405Y559542D02*
X1503335Y560791D01*
X1504420Y561417D01*
X1505660Y561625D01*
X1507210Y561208D01*
X1508295Y560167D01*
X1508605Y558917D01*
X1508450Y557666D01*
X1507830Y556625D01*
X1504730Y554542D01*
X1503335Y553083D01*
X1502405Y551000D01*
X1502095Y549125D01*
X1508605D01*
G01X1505350Y520775D02*
Y533275D01*
X1503490Y530775D01*
G01Y520775D02*
X1507210D01*
G01X1501940Y636675D02*
X1502870Y635216D01*
X1504110Y634383D01*
X1505505Y634175D01*
X1506745Y634383D01*
X1507985Y635425D01*
X1508760Y636675D01*
X1508915Y637925D01*
X1508605Y639383D01*
X1507520Y640425D01*
X1506435Y640842D01*
X1505040D01*
G01X1506435D02*
X1507365Y641467D01*
X1508140Y642508D01*
X1508450Y643758D01*
X1508140Y645008D01*
X1507365Y646050D01*
X1505970Y646675D01*
X1504575Y646467D01*
X1503180Y645633D01*
G01X1505350Y605825D02*
X1506435Y606033D01*
X1507675Y606658D01*
X1508450Y607700D01*
X1508760Y609158D01*
X1508450Y610616D01*
X1507520Y611867D01*
X1506125Y612492D01*
X1504575D01*
X1503645Y612908D01*
X1502870Y613950D01*
X1502560Y615408D01*
X1503025Y616867D01*
X1504110Y617908D01*
X1505350Y618325D01*
X1506590Y617908D01*
X1507675Y616867D01*
X1508140Y615408D01*
X1507830Y613950D01*
X1507055Y612908D01*
X1506125Y612492D01*
X1504575D01*
X1503180Y611867D01*
X1502250Y610616D01*
X1501940Y609158D01*
X1502250Y607700D01*
X1503025Y606658D01*
X1504265Y606033D01*
X1505350Y605825D01*
G01X1499150Y577475D02*
Y589975D01*
X1497290Y587475D01*
G01Y577475D02*
X1501010D01*
G01X1511550D02*
Y589975D01*
X1509690Y587475D01*
G01Y577475D02*
X1513410D01*
G01X1486750Y690875D02*
Y703375D01*
X1484890Y700875D01*
G01Y690875D02*
X1488610D01*
G01X1496205Y701292D02*
X1497135Y702541D01*
X1498220Y703167D01*
X1499460Y703375D01*
X1501010Y702958D01*
X1502095Y701917D01*
X1502405Y700667D01*
X1502250Y699416D01*
X1501630Y698375D01*
X1498530Y696292D01*
X1497135Y694833D01*
X1496205Y692750D01*
X1495895Y690875D01*
X1502405D01*
G01X1511240D02*
X1511550Y693583D01*
X1512015Y695875D01*
X1512635Y697958D01*
X1513410Y700250D01*
X1514650Y703375D01*
X1508450D01*
G01X1523950D02*
X1522710Y702958D01*
X1521780Y701917D01*
X1521160Y700667D01*
X1520695Y699000D01*
X1520540Y697125D01*
X1520695Y695250D01*
X1521160Y693583D01*
X1521780Y692333D01*
X1522710Y691292D01*
X1523950Y690875D01*
X1525190Y691292D01*
X1526120Y692333D01*
X1526740Y693583D01*
X1527205Y695250D01*
X1527360Y697125D01*
X1527205Y699000D01*
X1526740Y700667D01*
X1526120Y701917D01*
X1525190Y702958D01*
X1523950Y703375D01*
G01X1502715Y663983D02*
X1503800Y662942D01*
X1505040Y662525D01*
X1506280Y662942D01*
X1507365Y664191D01*
X1508140Y666067D01*
X1508450Y667942D01*
Y670233D01*
X1508140Y672108D01*
X1507365Y673775D01*
X1506435Y674608D01*
X1505350Y675025D01*
X1504110Y674608D01*
X1503180Y673775D01*
X1502560Y672525D01*
X1502250Y670858D01*
X1502560Y669400D01*
X1503335Y667942D01*
X1504265Y667108D01*
X1505350Y666900D01*
X1506590Y667316D01*
X1507520Y668358D01*
X1508450Y670233D01*
G01X1492950Y775925D02*
Y788425D01*
X1491090Y785925D01*
G01Y775925D02*
X1494810D01*
G01X1505350Y788425D02*
X1504110Y788008D01*
X1503180Y786967D01*
X1502560Y785717D01*
X1502095Y784050D01*
X1501940Y782175D01*
X1502095Y780300D01*
X1502560Y778633D01*
X1503180Y777383D01*
X1504110Y776342D01*
X1505350Y775925D01*
X1506590Y776342D01*
X1507520Y777383D01*
X1508140Y778633D01*
X1508605Y780300D01*
X1508760Y782175D01*
X1508605Y784050D01*
X1508140Y785717D01*
X1507520Y786967D01*
X1506590Y788008D01*
X1505350Y788425D01*
G01X1517750Y775925D02*
Y788425D01*
X1515890Y785925D01*
G01Y775925D02*
X1519610D01*
G01X1505350Y747575D02*
X1506435Y747783D01*
X1507675Y748408D01*
X1508450Y749450D01*
X1508760Y750908D01*
X1508450Y752366D01*
X1507520Y753617D01*
X1506125Y754242D01*
X1504575D01*
X1503645Y754658D01*
X1502870Y755700D01*
X1502560Y757158D01*
X1503025Y758617D01*
X1504110Y759658D01*
X1505350Y760075D01*
X1506590Y759658D01*
X1507675Y758617D01*
X1508140Y757158D01*
X1507830Y755700D01*
X1507055Y754658D01*
X1506125Y754242D01*
X1504575D01*
X1503180Y753617D01*
X1502250Y752366D01*
X1501940Y750908D01*
X1502250Y749450D01*
X1503025Y748408D01*
X1504265Y747783D01*
X1505350Y747575D01*
G01X1490005Y729642D02*
X1490935Y730891D01*
X1492020Y731517D01*
X1493260Y731725D01*
X1494810Y731308D01*
X1495895Y730267D01*
X1496205Y729017D01*
X1496050Y727766D01*
X1495430Y726725D01*
X1492330Y724642D01*
X1490935Y723183D01*
X1490005Y721100D01*
X1489695Y719225D01*
X1496205D01*
G01X1505350Y731725D02*
X1504110Y731308D01*
X1503180Y730267D01*
X1502560Y729017D01*
X1502095Y727350D01*
X1501940Y725475D01*
X1502095Y723600D01*
X1502560Y721933D01*
X1503180Y720683D01*
X1504110Y719642D01*
X1505350Y719225D01*
X1506590Y719642D01*
X1507520Y720683D01*
X1508140Y721933D01*
X1508605Y723600D01*
X1508760Y725475D01*
X1508605Y727350D01*
X1508140Y729017D01*
X1507520Y730267D01*
X1506590Y731308D01*
X1505350Y731725D01*
G01X1517750D02*
X1516510Y731308D01*
X1515580Y730267D01*
X1514960Y729017D01*
X1514495Y727350D01*
X1514340Y725475D01*
X1514495Y723600D01*
X1514960Y721933D01*
X1515580Y720683D01*
X1516510Y719642D01*
X1517750Y719225D01*
X1518990Y719642D01*
X1519920Y720683D01*
X1520540Y721933D01*
X1521005Y723600D01*
X1521160Y725475D01*
X1521005Y727350D01*
X1520540Y729017D01*
X1519920Y730267D01*
X1518990Y731308D01*
X1517750Y731725D01*
G01X1486750Y832625D02*
Y845125D01*
X1484890Y842625D01*
G01Y832625D02*
X1488610D01*
G01X1495740Y835125D02*
X1496670Y833666D01*
X1497910Y832833D01*
X1499305Y832625D01*
X1500545Y832833D01*
X1501785Y833875D01*
X1502560Y835125D01*
X1502715Y836375D01*
X1502405Y837833D01*
X1501320Y838875D01*
X1500235Y839292D01*
X1498840D01*
G01X1500235D02*
X1501165Y839917D01*
X1501940Y840958D01*
X1502250Y842208D01*
X1501940Y843458D01*
X1501165Y844500D01*
X1499770Y845125D01*
X1498375Y844917D01*
X1496980Y844083D01*
G01X1508140Y835125D02*
X1509070Y833666D01*
X1510310Y832833D01*
X1511705Y832625D01*
X1512945Y832833D01*
X1514185Y833875D01*
X1514960Y835125D01*
X1515115Y836375D01*
X1514805Y837833D01*
X1513720Y838875D01*
X1512635Y839292D01*
X1511240D01*
G01X1512635D02*
X1513565Y839917D01*
X1514340Y840958D01*
X1514650Y842208D01*
X1514340Y843458D01*
X1513565Y844500D01*
X1512170Y845125D01*
X1510775Y844917D01*
X1509380Y844083D01*
G01X1521005Y837833D02*
X1522090Y839292D01*
X1523020Y840125D01*
X1524260Y840542D01*
X1525345Y840125D01*
X1526120Y839292D01*
X1526740Y838042D01*
X1526895Y836583D01*
X1526740Y835333D01*
X1526120Y834083D01*
X1525190Y833042D01*
X1524105Y832625D01*
X1522865Y833042D01*
X1521780Y834291D01*
X1521160Y836167D01*
X1521005Y838250D01*
X1521315Y840958D01*
X1521780Y842417D01*
X1522555Y843875D01*
X1523640Y844917D01*
X1524725Y845125D01*
X1525810Y844708D01*
X1526585Y843667D01*
G01X1501010Y804275D02*
Y816775D01*
X1495275Y807817D01*
X1503025D01*
G01X1511550Y804275D02*
Y816775D01*
X1509690Y814275D01*
G01Y804275D02*
X1513410D01*
G01X1492950Y890750D02*
X1491710Y890958D01*
X1490625Y891791D01*
X1489695Y893042D01*
X1489075Y894500D01*
X1488765Y896167D01*
Y897833D01*
X1489075Y899500D01*
X1489695Y900958D01*
X1490625Y902208D01*
X1491710Y903042D01*
X1492950Y903250D01*
X1494190Y903042D01*
X1495275Y902208D01*
X1496205Y900958D01*
X1496825Y899500D01*
X1497135Y897833D01*
Y896167D01*
X1496825Y894500D01*
X1496205Y893042D01*
X1495275Y891791D01*
X1494190Y890958D01*
X1492950Y890750D01*
G01X1494190Y894083D02*
X1496050Y890750D01*
G01X1505350Y903250D02*
Y890750D01*
G01X1501785Y903250D02*
X1508915D01*
G01X1517750Y890750D02*
Y896375D01*
X1514650Y903250D01*
G01X1520850D02*
X1517750Y896375D01*
G01X1490005Y871392D02*
X1490935Y872641D01*
X1492020Y873267D01*
X1493260Y873475D01*
X1494810Y873058D01*
X1495895Y872017D01*
X1496205Y870767D01*
X1496050Y869516D01*
X1495430Y868475D01*
X1492330Y866392D01*
X1490935Y864933D01*
X1490005Y862850D01*
X1489695Y860975D01*
X1496205D01*
G01X1505040D02*
X1505350Y863683D01*
X1505815Y865975D01*
X1506435Y868058D01*
X1507210Y870350D01*
X1508450Y873475D01*
X1502250D01*
G01X1514340Y863475D02*
X1515270Y862016D01*
X1516510Y861183D01*
X1517905Y860975D01*
X1519145Y861183D01*
X1520385Y862225D01*
X1521160Y863475D01*
X1521315Y864725D01*
X1521005Y866183D01*
X1519920Y867225D01*
X1518835Y867642D01*
X1517440D01*
G01X1518835D02*
X1519765Y868267D01*
X1520540Y869308D01*
X1520850Y870558D01*
X1520540Y871808D01*
X1519765Y872850D01*
X1518370Y873475D01*
X1516975Y873267D01*
X1515580Y872433D01*
G01X3937Y0D02*
X116260D01*
G01X0Y3937D02*
G03X3937Y0I3937J0D01*
G01X0Y723480D02*
Y3937D01*
G01X416Y725241D02*
G03X0Y723480I3521J-1761D01*
G01X18597Y761603D02*
X416Y725241D01*
G01X22118Y763780D02*
G03X18597Y761603I1J-3937D01*
G01X386149Y763780D02*
X22118D01*
G01X120197Y3937D02*
Y429331D01*
G01X116260Y0D02*
G03X120197Y3937I0J3937D01*
G01X128071D02*
G03X132008Y0I3937J0D01*
G01X128071Y43308D02*
G03X120197I-3937J0D01*
G01X132008Y0D02*
X275709D01*
G01X128071Y3937D02*
Y43308D01*
G01X120197Y74016D02*
G03X128071I3937J0D01*
G01D02*
Y425394D01*
G01X74697Y254419D02*
X75097Y254819D01*
X75564Y255019D01*
X76097Y255086D01*
X76764Y254953D01*
X77231Y254619D01*
X77364Y254219D01*
X77297Y253819D01*
X77031Y253486D01*
X75697Y252819D01*
X75097Y252353D01*
X74697Y251686D01*
X74564Y251086D01*
X77364D01*
G01X79297Y252753D02*
X79764Y253219D01*
X80164Y253486D01*
X80697Y253619D01*
X81164Y253486D01*
X81497Y253219D01*
X81764Y252819D01*
X81831Y252353D01*
X81764Y251953D01*
X81497Y251553D01*
X81097Y251219D01*
X80631Y251086D01*
X80097Y251219D01*
X79631Y251619D01*
X79364Y252219D01*
X79297Y252886D01*
X79431Y253753D01*
X79631Y254219D01*
X79964Y254686D01*
X80431Y255019D01*
X80897Y255086D01*
X81364Y254953D01*
X81697Y254619D01*
G01X85164Y251086D02*
X85631Y251153D01*
X86164Y251353D01*
X86497Y251686D01*
X86631Y252153D01*
X86497Y252619D01*
X86097Y253019D01*
X85497Y253219D01*
X84831D01*
X84431Y253353D01*
X84097Y253686D01*
X83964Y254153D01*
X84164Y254619D01*
X84631Y254953D01*
X85164Y255086D01*
X85697Y254953D01*
X86164Y254619D01*
X86364Y254153D01*
X86231Y253686D01*
X85897Y253353D01*
X85497Y253219D01*
X84831D01*
X84231Y253019D01*
X83831Y252619D01*
X83697Y252153D01*
X83831Y251686D01*
X84164Y251353D01*
X84697Y251153D01*
X85164Y251086D01*
G01X88364D02*
X91164Y255086D01*
G01X88364D02*
X91164Y251086D01*
G01X94364D02*
Y255086D01*
X93564Y254286D01*
G01Y251086D02*
X95164D01*
G01X97497Y251886D02*
X97897Y251419D01*
X98431Y251153D01*
X99031Y251086D01*
X99564Y251153D01*
X100097Y251486D01*
X100431Y251886D01*
X100497Y252286D01*
X100364Y252753D01*
X99897Y253086D01*
X99431Y253219D01*
X98831D01*
G01X99431D02*
X99831Y253419D01*
X100164Y253753D01*
X100297Y254153D01*
X100164Y254553D01*
X99831Y254886D01*
X99231Y255086D01*
X98631Y255019D01*
X98031Y254753D01*
G01X104364Y251086D02*
Y255086D01*
X101897Y252219D01*
X105231D01*
G01X124134Y433268D02*
X283583D01*
G01X124134D02*
G03X120197Y429331I0J-3937D01*
G01X188504Y425394D02*
X128071D01*
G01X152497Y21054D02*
G03I-4291J0D01*
G01X188504Y425394D02*
G03Y433268I0J3937D01*
G01X275709Y0D02*
G03X279646Y3937I0J3937D01*
G01X287520Y43308D02*
G03X279646I-3937J0D01*
G01Y3937D02*
Y43308D01*
G01Y74016D02*
G03X287520I3937J0D01*
G01X279646D02*
Y425394D01*
G01X265438Y405580D02*
G03I-4291J0D01*
G01X287520Y429331D02*
G03X283583Y433268I-3937J0D01*
G01X219213D02*
G03Y425394I0J-3937D01*
G01X279646D02*
X219213D01*
G01X291457Y0D02*
X921260D01*
G01X287520Y3937D02*
G03X291457Y0I3937J0D01*
G01X287520Y429331D02*
Y3937D01*
G01X321114Y72979D02*
X321514Y72512D01*
X322048Y72246D01*
X322648Y72179D01*
X323181Y72246D01*
X323714Y72579D01*
X324048Y72979D01*
X324114Y73379D01*
X323981Y73846D01*
X323514Y74179D01*
X323048Y74312D01*
X322448D01*
G01X323048D02*
X323448Y74512D01*
X323781Y74846D01*
X323914Y75246D01*
X323781Y75646D01*
X323448Y75979D01*
X322848Y76179D01*
X322248Y76112D01*
X321648Y75846D01*
G01X325914Y75512D02*
X326314Y75912D01*
X326781Y76112D01*
X327314Y76179D01*
X327981Y76046D01*
X328448Y75712D01*
X328581Y75312D01*
X328514Y74912D01*
X328248Y74579D01*
X326914Y73912D01*
X326314Y73446D01*
X325914Y72779D01*
X325781Y72179D01*
X328581D01*
G01X330381D02*
X333181Y76179D01*
G01X330381D02*
X333181Y72179D01*
G01X334914Y72779D02*
X335314Y72446D01*
X335781Y72246D01*
X336381Y72179D01*
X336981Y72312D01*
X337448Y72579D01*
X337781Y73046D01*
X337848Y73579D01*
X337714Y74112D01*
X337381Y74446D01*
X336914Y74712D01*
X336448Y74779D01*
X335981Y74712D01*
X335381Y74446D01*
X335581Y76179D01*
X337381D01*
G01X339714Y73846D02*
X340181Y74312D01*
X340581Y74579D01*
X341114Y74712D01*
X341581Y74579D01*
X341914Y74312D01*
X342181Y73912D01*
X342248Y73446D01*
X342181Y73046D01*
X341914Y72646D01*
X341514Y72312D01*
X341048Y72179D01*
X340514Y72312D01*
X340048Y72712D01*
X339781Y73312D01*
X339714Y73979D01*
X339848Y74846D01*
X340048Y75312D01*
X340381Y75779D01*
X340848Y76112D01*
X341314Y76179D01*
X341781Y76046D01*
X342114Y75712D01*
G01X321164Y67453D02*
X321564Y66986D01*
X322098Y66720D01*
X322698Y66653D01*
X323231Y66720D01*
X323764Y67053D01*
X324098Y67453D01*
X324164Y67853D01*
X324031Y68320D01*
X323564Y68653D01*
X323098Y68786D01*
X322498D01*
G01X323098D02*
X323498Y68986D01*
X323831Y69320D01*
X323964Y69720D01*
X323831Y70120D01*
X323498Y70453D01*
X322898Y70653D01*
X322298Y70586D01*
X321698Y70320D01*
G01X325964Y69986D02*
X326364Y70386D01*
X326831Y70586D01*
X327364Y70653D01*
X328031Y70520D01*
X328498Y70186D01*
X328631Y69786D01*
X328564Y69386D01*
X328298Y69053D01*
X326964Y68386D01*
X326364Y67920D01*
X325964Y67253D01*
X325831Y66653D01*
X328631D01*
G01X330431D02*
X333231Y70653D01*
G01X330431D02*
X333231Y66653D01*
G01X336431D02*
X336898Y66720D01*
X337431Y66920D01*
X337764Y67253D01*
X337898Y67720D01*
X337764Y68186D01*
X337364Y68586D01*
X336764Y68786D01*
X336098D01*
X335698Y68920D01*
X335364Y69253D01*
X335231Y69720D01*
X335431Y70186D01*
X335898Y70520D01*
X336431Y70653D01*
X336964Y70520D01*
X337431Y70186D01*
X337631Y69720D01*
X337498Y69253D01*
X337164Y68920D01*
X336764Y68786D01*
X336098D01*
X335498Y68586D01*
X335098Y68186D01*
X334964Y67720D01*
X335098Y67253D01*
X335431Y66920D01*
X335964Y66720D01*
X336431Y66653D01*
G01X339564Y67453D02*
X339964Y66986D01*
X340498Y66720D01*
X341098Y66653D01*
X341631Y66720D01*
X342164Y67053D01*
X342498Y67453D01*
X342564Y67853D01*
X342431Y68320D01*
X341964Y68653D01*
X341498Y68786D01*
X340898D01*
G01X341498D02*
X341898Y68986D01*
X342231Y69320D01*
X342364Y69720D01*
X342231Y70120D01*
X341898Y70453D01*
X341298Y70653D01*
X340698Y70586D01*
X340098Y70320D01*
G01X294185Y429616D02*
X294585Y430016D01*
X295052Y430216D01*
X295585Y430283D01*
X296252Y430150D01*
X296719Y429816D01*
X296852Y429416D01*
X296785Y429016D01*
X296519Y428683D01*
X295185Y428016D01*
X294585Y427550D01*
X294185Y426883D01*
X294052Y426283D01*
X296852D01*
G01X298785Y427950D02*
X299252Y428416D01*
X299652Y428683D01*
X300185Y428816D01*
X300652Y428683D01*
X300985Y428416D01*
X301252Y428016D01*
X301319Y427550D01*
X301252Y427150D01*
X300985Y426750D01*
X300585Y426416D01*
X300119Y426283D01*
X299585Y426416D01*
X299119Y426816D01*
X298852Y427416D01*
X298785Y428083D01*
X298919Y428950D01*
X299119Y429416D01*
X299452Y429883D01*
X299919Y430216D01*
X300385Y430283D01*
X300852Y430150D01*
X301185Y429816D01*
G01X304652Y426283D02*
X305119Y426350D01*
X305652Y426550D01*
X305985Y426883D01*
X306119Y427350D01*
X305985Y427816D01*
X305585Y428216D01*
X304985Y428416D01*
X304319D01*
X303919Y428550D01*
X303585Y428883D01*
X303452Y429350D01*
X303652Y429816D01*
X304119Y430150D01*
X304652Y430283D01*
X305185Y430150D01*
X305652Y429816D01*
X305852Y429350D01*
X305719Y428883D01*
X305385Y428550D01*
X304985Y428416D01*
X304319D01*
X303719Y428216D01*
X303319Y427816D01*
X303185Y427350D01*
X303319Y426883D01*
X303652Y426550D01*
X304185Y426350D01*
X304652Y426283D01*
G01X307852D02*
X310652Y430283D01*
G01X307852D02*
X310652Y426283D01*
G01X313852D02*
Y430283D01*
X313052Y429483D01*
G01Y426283D02*
X314652D01*
G01X316985Y427083D02*
X317385Y426616D01*
X317919Y426350D01*
X318519Y426283D01*
X319052Y426350D01*
X319585Y426683D01*
X319919Y427083D01*
X319985Y427483D01*
X319852Y427950D01*
X319385Y428283D01*
X318919Y428416D01*
X318319D01*
G01X318919D02*
X319319Y428616D01*
X319652Y428950D01*
X319785Y429350D01*
X319652Y429750D01*
X319319Y430083D01*
X318719Y430283D01*
X318119Y430216D01*
X317519Y429950D01*
G01X323852Y426283D02*
Y430283D01*
X321385Y427416D01*
X324719D01*
G01X357252Y72479D02*
X357652Y72012D01*
X358186Y71746D01*
X358786Y71679D01*
X359319Y71746D01*
X359852Y72079D01*
X360186Y72479D01*
X360252Y72879D01*
X360119Y73346D01*
X359652Y73679D01*
X359186Y73812D01*
X358586D01*
G01X359186D02*
X359586Y74012D01*
X359919Y74346D01*
X360052Y74746D01*
X359919Y75146D01*
X359586Y75479D01*
X358986Y75679D01*
X358386Y75612D01*
X357786Y75346D01*
G01X362052Y75012D02*
X362452Y75412D01*
X362919Y75612D01*
X363452Y75679D01*
X364119Y75546D01*
X364586Y75212D01*
X364719Y74812D01*
X364652Y74412D01*
X364386Y74079D01*
X363052Y73412D01*
X362452Y72946D01*
X362052Y72279D01*
X361919Y71679D01*
X364719D01*
G01X366519D02*
X369319Y75679D01*
G01X366519D02*
X369319Y71679D01*
G01X372519D02*
X372986Y71746D01*
X373519Y71946D01*
X373852Y72279D01*
X373986Y72746D01*
X373852Y73212D01*
X373452Y73612D01*
X372852Y73812D01*
X372186D01*
X371786Y73946D01*
X371452Y74279D01*
X371319Y74746D01*
X371519Y75212D01*
X371986Y75546D01*
X372519Y75679D01*
X373052Y75546D01*
X373519Y75212D01*
X373719Y74746D01*
X373586Y74279D01*
X373252Y73946D01*
X372852Y73812D01*
X372186D01*
X371586Y73612D01*
X371186Y73212D01*
X371052Y72746D01*
X371186Y72279D01*
X371519Y71946D01*
X372052Y71746D01*
X372519Y71679D01*
G01X375652Y72479D02*
X376052Y72012D01*
X376586Y71746D01*
X377186Y71679D01*
X377719Y71746D01*
X378252Y72079D01*
X378586Y72479D01*
X378652Y72879D01*
X378519Y73346D01*
X378052Y73679D01*
X377586Y73812D01*
X376986D01*
G01X377586D02*
X377986Y74012D01*
X378319Y74346D01*
X378452Y74746D01*
X378319Y75146D01*
X377986Y75479D01*
X377386Y75679D01*
X376786Y75612D01*
X376186Y75346D01*
G01X357402Y66953D02*
X357802Y66486D01*
X358336Y66220D01*
X358936Y66153D01*
X359469Y66220D01*
X360002Y66553D01*
X360336Y66953D01*
X360402Y67353D01*
X360269Y67820D01*
X359802Y68153D01*
X359336Y68286D01*
X358736D01*
G01X359336D02*
X359736Y68486D01*
X360069Y68820D01*
X360202Y69220D01*
X360069Y69620D01*
X359736Y69953D01*
X359136Y70153D01*
X358536Y70086D01*
X357936Y69820D01*
G01X362202Y69486D02*
X362602Y69886D01*
X363069Y70086D01*
X363602Y70153D01*
X364269Y70020D01*
X364736Y69686D01*
X364869Y69286D01*
X364802Y68886D01*
X364536Y68553D01*
X363202Y67886D01*
X362602Y67420D01*
X362202Y66753D01*
X362069Y66153D01*
X364869D01*
G01X366669D02*
X369469Y70153D01*
G01X366669D02*
X369469Y66153D01*
G01X371202Y66753D02*
X371602Y66420D01*
X372069Y66220D01*
X372669Y66153D01*
X373269Y66286D01*
X373736Y66553D01*
X374069Y67020D01*
X374136Y67553D01*
X374002Y68086D01*
X373669Y68420D01*
X373202Y68686D01*
X372736Y68753D01*
X372269Y68686D01*
X371669Y68420D01*
X371869Y70153D01*
X373669D01*
G01X376002Y67820D02*
X376469Y68286D01*
X376869Y68553D01*
X377402Y68686D01*
X377869Y68553D01*
X378202Y68286D01*
X378469Y67886D01*
X378536Y67420D01*
X378469Y67020D01*
X378202Y66620D01*
X377802Y66286D01*
X377336Y66153D01*
X376802Y66286D01*
X376336Y66686D01*
X376069Y67286D01*
X376002Y67953D01*
X376136Y68820D01*
X376336Y69286D01*
X376669Y69753D01*
X377136Y70086D01*
X377602Y70153D01*
X378069Y70020D01*
X378402Y69686D01*
G01X558799Y119154D02*
X419153D01*
Y185571D01*
X558799D01*
Y119154D01*
G01X595332Y198516D02*
Y194516D01*
X593732D01*
X593199Y194716D01*
X592799Y195183D01*
X592666Y195716D01*
X592799Y196249D01*
X593132Y196649D01*
X593732Y196849D01*
X595332D01*
G01X590332Y198516D02*
Y195849D01*
G01Y196383D02*
X589999Y196116D01*
X589666Y195916D01*
X589199Y195849D01*
X588866Y195916D01*
X588466Y196116D01*
G01X585799Y196716D02*
X583666D01*
X583866Y196249D01*
X584199Y195983D01*
X584666Y195849D01*
X585132Y195916D01*
X585532Y196116D01*
X585799Y196583D01*
X585932Y196983D01*
Y197383D01*
X585799Y197783D01*
X585466Y198183D01*
X585066Y198449D01*
X584599Y198516D01*
X584132Y198383D01*
X583666Y197983D01*
G01X581199Y198049D02*
X580866Y198316D01*
X580399Y198516D01*
X579999D01*
X579599Y198383D01*
X579332Y198183D01*
X579199Y197916D01*
X579266Y197516D01*
X579532Y197316D01*
X580732Y196916D01*
X580999Y196449D01*
X580866Y196116D01*
X580599Y195916D01*
X580199Y195849D01*
X579799Y195916D01*
X579399Y196116D01*
G01X576599Y198049D02*
X576266Y198316D01*
X575799Y198516D01*
X575399D01*
X574999Y198383D01*
X574732Y198183D01*
X574599Y197916D01*
X574666Y197516D01*
X574932Y197316D01*
X576132Y196916D01*
X576399Y196449D01*
X576266Y196116D01*
X575999Y195916D01*
X575599Y195849D01*
X575199Y195916D01*
X574799Y196116D01*
G01X571866Y197183D02*
X570132D01*
G01X566799Y198516D02*
Y195116D01*
X566666Y194783D01*
X566399Y194583D01*
X565999Y194516D01*
X565599Y194649D01*
X565399Y194983D01*
G01X566199Y196116D02*
X567532D01*
G01X561799Y195849D02*
Y198516D01*
G01Y194783D02*
X561932Y194716D01*
Y194583D01*
X561799Y194516D01*
X561666Y194583D01*
Y194716D01*
X561799Y194783D01*
G01X557199Y194516D02*
Y198516D01*
G01X558132Y195849D02*
X556266D01*
G01X549332Y198516D02*
Y194516D01*
X547732D01*
X547199Y194716D01*
X546799Y195183D01*
X546666Y195716D01*
X546799Y196249D01*
X547132Y196649D01*
X547732Y196849D01*
X549332D01*
G01X543399Y194516D02*
Y198516D01*
G01X544932Y194516D02*
X541866D01*
G01X540199Y198516D02*
Y194516D01*
G01X537399D02*
Y198516D01*
G01Y196516D02*
X540199D01*
G01X530732Y198516D02*
Y194516D01*
G01X528599Y195849D02*
X530732Y197383D01*
G01X529866Y196783D02*
X528466Y198516D01*
G01X525999Y196716D02*
X523866D01*
X524066Y196249D01*
X524399Y195983D01*
X524866Y195849D01*
X525332Y195916D01*
X525732Y196116D01*
X525999Y196583D01*
X526132Y196983D01*
Y197383D01*
X525999Y197783D01*
X525666Y198183D01*
X525266Y198449D01*
X524799Y198516D01*
X524332Y198383D01*
X523866Y197983D01*
G01X521399Y196716D02*
X519266D01*
X519466Y196249D01*
X519799Y195983D01*
X520266Y195849D01*
X520732Y195916D01*
X521132Y196116D01*
X521399Y196583D01*
X521532Y196983D01*
Y197383D01*
X521399Y197783D01*
X521066Y198183D01*
X520666Y198449D01*
X520199Y198516D01*
X519732Y198383D01*
X519266Y197983D01*
G01X516999Y199849D02*
Y195849D01*
G01Y196449D02*
X516666Y196116D01*
X516332Y195916D01*
X515799Y195849D01*
X515332Y195916D01*
X514866Y196249D01*
X514666Y196716D01*
X514599Y197183D01*
X514666Y197649D01*
X514866Y198116D01*
X515266Y198383D01*
X515799Y198516D01*
X516266Y198449D01*
X516732Y198249D01*
X516999Y197983D01*
G01X507732Y198516D02*
Y194516D01*
G01Y196449D02*
X507399Y196116D01*
X507066Y195916D01*
X506532Y195849D01*
X506132Y195916D01*
X505666Y196183D01*
X505466Y196583D01*
Y198516D01*
G01X501999D02*
X502399Y198449D01*
X502799Y198183D01*
X503066Y197716D01*
X503199Y197183D01*
X503066Y196649D01*
X502799Y196183D01*
X502399Y195916D01*
X501999Y195849D01*
X501599Y195916D01*
X501199Y196183D01*
X500932Y196649D01*
X500866Y197183D01*
X500932Y197716D01*
X501199Y198183D01*
X501599Y198449D01*
X501999Y198516D01*
G01X497399D02*
Y194516D01*
G01X493799Y196716D02*
X491666D01*
X491866Y196249D01*
X492199Y195983D01*
X492666Y195849D01*
X493132Y195916D01*
X493532Y196116D01*
X493799Y196583D01*
X493932Y196983D01*
Y197383D01*
X493799Y197783D01*
X493466Y198183D01*
X493066Y198449D01*
X492599Y198516D01*
X492132Y198383D01*
X491666Y197983D01*
G01X484599Y198049D02*
X484266Y198316D01*
X483799Y198516D01*
X483399D01*
X482999Y198383D01*
X482732Y198183D01*
X482599Y197916D01*
X482666Y197516D01*
X482932Y197316D01*
X484132Y196916D01*
X484399Y196449D01*
X484266Y196116D01*
X483999Y195916D01*
X483599Y195849D01*
X483199Y195916D01*
X482799Y196116D01*
G01X478999Y195849D02*
Y198516D01*
G01Y194783D02*
X479132Y194716D01*
Y194583D01*
X478999Y194516D01*
X478866Y194583D01*
Y194716D01*
X478999Y194783D01*
G01X475399Y195849D02*
X473399D01*
X475399Y198516D01*
X473399D01*
G01X470799Y196716D02*
X468666D01*
X468866Y196249D01*
X469199Y195983D01*
X469666Y195849D01*
X470132Y195916D01*
X470532Y196116D01*
X470799Y196583D01*
X470932Y196983D01*
Y197383D01*
X470799Y197783D01*
X470466Y198183D01*
X470066Y198449D01*
X469599Y198516D01*
X469132Y198383D01*
X468666Y197983D01*
G01X460599Y194516D02*
Y198516D01*
G01X461532Y195849D02*
X459666D01*
G01X455999Y198516D02*
X456399Y198449D01*
X456799Y198183D01*
X457066Y197716D01*
X457199Y197183D01*
X457066Y196649D01*
X456799Y196183D01*
X456399Y195916D01*
X455999Y195849D01*
X455599Y195916D01*
X455199Y196183D01*
X454932Y196649D01*
X454866Y197183D01*
X454932Y197716D01*
X455199Y198183D01*
X455599Y198449D01*
X455999Y198516D01*
G01X451399D02*
Y194516D01*
G01X447799Y196716D02*
X445666D01*
X445866Y196249D01*
X446199Y195983D01*
X446666Y195849D01*
X447132Y195916D01*
X447532Y196116D01*
X447799Y196583D01*
X447932Y196983D01*
Y197383D01*
X447799Y197783D01*
X447466Y198183D01*
X447066Y198449D01*
X446599Y198516D01*
X446132Y198383D01*
X445666Y197983D01*
G01X443132Y198516D02*
Y195849D01*
G01Y196383D02*
X442799Y196116D01*
X442466Y195916D01*
X441999Y195849D01*
X441666Y195916D01*
X441266Y196116D01*
G01X436399Y198516D02*
Y195849D01*
G01Y196316D02*
X436666Y196049D01*
X437066Y195916D01*
X437532Y195849D01*
X437999Y195983D01*
X438399Y196249D01*
X438666Y196649D01*
X438799Y197183D01*
X438666Y197716D01*
X438399Y198116D01*
X437999Y198383D01*
X437532Y198516D01*
X437066Y198449D01*
X436666Y198249D01*
X436399Y197983D01*
G01X434132Y198516D02*
Y195849D01*
G01Y196516D02*
X433866Y196183D01*
X433466Y195916D01*
X432932Y195849D01*
X432466Y195916D01*
X432066Y196183D01*
X431866Y196649D01*
Y198516D01*
G01X427332Y196183D02*
X427799Y195916D01*
X428199Y195849D01*
X428732Y195983D01*
X429132Y196249D01*
X429399Y196716D01*
X429466Y197183D01*
X429399Y197649D01*
X429132Y198049D01*
X428732Y198383D01*
X428199Y198516D01*
X427732Y198383D01*
X427332Y198116D01*
G01X424799Y196716D02*
X422666D01*
X422866Y196249D01*
X423199Y195983D01*
X423666Y195849D01*
X424132Y195916D01*
X424532Y196116D01*
X424799Y196583D01*
X424932Y196983D01*
Y197383D01*
X424799Y197783D01*
X424466Y198183D01*
X424066Y198449D01*
X423599Y198516D01*
X423132Y198383D01*
X422666Y197983D01*
G01X415332Y197183D02*
X413732D01*
G01X414599Y196316D02*
Y198049D01*
G01X411199Y198649D02*
X408799Y194516D01*
G01X406266Y197183D02*
X404532D01*
G01X402066Y195183D02*
X401666Y194783D01*
X401199Y194583D01*
X400666Y194516D01*
X399999Y194649D01*
X399532Y194983D01*
X399399Y195383D01*
X399466Y195783D01*
X399732Y196116D01*
X401066Y196783D01*
X401666Y197249D01*
X402066Y197916D01*
X402199Y198516D01*
X399399D01*
G01X393599D02*
Y195849D01*
G01Y196583D02*
X393399Y196249D01*
X393066Y195983D01*
X392599Y195849D01*
X392132Y195983D01*
X391799Y196249D01*
X391599Y196583D01*
Y198516D01*
G01Y196583D02*
X391399Y196249D01*
X391066Y195983D01*
X390599Y195849D01*
X390132Y195983D01*
X389799Y196249D01*
X389599Y196649D01*
Y198516D01*
G01X386999Y195849D02*
Y198516D01*
G01Y194783D02*
X387132Y194716D01*
Y194583D01*
X386999Y194516D01*
X386866Y194583D01*
Y194716D01*
X386999Y194783D01*
G01X382399Y198516D02*
Y194516D01*
G01X378799Y198049D02*
X378466Y198316D01*
X377999Y198516D01*
X377599D01*
X377199Y198383D01*
X376932Y198183D01*
X376799Y197916D01*
X376866Y197516D01*
X377132Y197316D01*
X378332Y196916D01*
X378599Y196449D01*
X378466Y196116D01*
X378199Y195916D01*
X377799Y195849D01*
X377399Y195916D01*
X376999Y196116D01*
G01X562299Y188977D02*
X414299D01*
G01X408268Y188976D02*
Y723480D01*
G01Y188976D02*
G03X412205I1968J0D01*
G01X564173D02*
X412205D01*
G01X416142Y348379D02*
Y196851D01*
G01D02*
X560237D01*
G01X416142Y348379D02*
G03X408268I-3937J0D01*
G01Y379088D02*
G03X416142I3937J0D01*
G01Y688303D02*
Y379088D01*
G01Y688303D02*
G03X408268I-3937J0D01*
G01X389671Y761603D02*
G03X386149Y763780I-3522J-1760D01*
G01X407852Y725241D02*
X389671Y761603D01*
G01X408268Y723480D02*
G03X407852Y725241I-3937J0D01*
G01X524242Y763780D02*
X403757D01*
G01D02*
G03X400235Y758082I0J-3937D01*
G01X408268Y719012D02*
G03X416142I3937J0D01*
G01Y723480D02*
G03X414895Y728763I-11811J1D01*
G01X400235Y758082D02*
X414895Y728763D01*
G01X416142Y723480D02*
Y719012D01*
G01X487899Y195571D02*
Y185871D01*
X482899Y190871D01*
X492899D01*
X487899Y185871D01*
G01X490789Y356293D02*
G03I-4291J0D01*
G01X542194Y203859D02*
X541661Y204192D01*
X541061Y204392D01*
X540527D01*
X539994Y204192D01*
X539594Y203859D01*
X539394Y203392D01*
X539527Y202925D01*
X539861Y202525D01*
X540461Y202259D01*
X541261Y202125D01*
X541727Y201859D01*
X541927Y201392D01*
X541794Y200925D01*
X541461Y200592D01*
X540994Y200392D01*
X540527D01*
X540061Y200525D01*
X539661Y200859D01*
G01X536194Y204392D02*
Y200392D01*
G01X531594Y201725D02*
Y204392D01*
G01Y200659D02*
X531727Y200592D01*
Y200459D01*
X531594Y200392D01*
X531461Y200459D01*
Y200592D01*
X531594Y200659D01*
G01X526994Y200392D02*
Y204392D01*
G01X527927Y201725D02*
X526061D01*
G01X534010Y189308D02*
X536010Y191308D01*
X532010D01*
X534010Y189308D01*
X534069Y200535D01*
G01X564173Y188976D02*
G03X568110I1968J0D01*
G01Y589622D02*
Y188976D01*
G01X560237Y261975D02*
Y196851D01*
G01X568111Y261975D02*
G03X560237I-3937J0D01*
G01Y292684D02*
G03X568111I3937J0D01*
G01X560237Y551040D02*
Y292684D01*
G01X568111Y551040D02*
G03X560237I-3937J0D01*
G01X568526Y591382D02*
G03X568110Y589622I3521J-1761D01*
G01X586707Y627745D02*
X568526Y591382D01*
G01X560237Y581748D02*
G03X568111I3937J0D01*
G01X561484Y594905D02*
G03X560237Y589622I10564J-5282D01*
G01D02*
Y581748D01*
G01X579665Y631267D02*
X561484Y594904D01*
G01X524242Y763780D02*
G03X532116I3937J0D01*
G01X834646D02*
X532116D01*
G01X590228Y629921D02*
G03X586707Y627745I0J-3937D01*
G01X842520Y629921D02*
X590228D01*
G01X590229Y637796D02*
G03X579665Y631268I0J-11812D01*
G01X590229Y637796D02*
X838583D01*
G01X722749Y69911D02*
X718749D01*
X719549Y69111D01*
G01X722749D02*
Y70711D01*
G01Y74511D02*
X722682Y74978D01*
X722482Y75511D01*
X722149Y75844D01*
X721682Y75978D01*
X721216Y75844D01*
X720816Y75444D01*
X720616Y74844D01*
Y74178D01*
X720482Y73778D01*
X720149Y73444D01*
X719682Y73311D01*
X719216Y73511D01*
X718882Y73978D01*
X718749Y74511D01*
X718882Y75044D01*
X719216Y75511D01*
X719682Y75711D01*
X720149Y75578D01*
X720482Y75244D01*
X720616Y74844D01*
Y74178D01*
X720816Y73578D01*
X721216Y73178D01*
X721682Y73044D01*
X722149Y73178D01*
X722482Y73511D01*
X722682Y74044D01*
X722749Y74511D01*
G01X722282Y77978D02*
X722616Y78444D01*
X722749Y78978D01*
X722616Y79511D01*
X722216Y79978D01*
X721616Y80311D01*
X721016Y80444D01*
X720282D01*
X719682Y80311D01*
X719149Y79978D01*
X718882Y79578D01*
X718749Y79111D01*
X718882Y78578D01*
X719149Y78178D01*
X719549Y77911D01*
X720082Y77778D01*
X720549Y77911D01*
X721016Y78244D01*
X721282Y78644D01*
X721349Y79111D01*
X721216Y79644D01*
X720882Y80044D01*
X720282Y80444D01*
G01X722749Y82311D02*
X718749Y85111D01*
G01Y82311D02*
X722749Y85111D01*
G01Y88311D02*
X718749D01*
X719549Y87511D01*
G01X722749D02*
Y89111D01*
G01X719416Y91644D02*
X719016Y92044D01*
X718816Y92511D01*
X718749Y93044D01*
X718882Y93711D01*
X719216Y94178D01*
X719616Y94311D01*
X720016Y94244D01*
X720349Y93978D01*
X721016Y92644D01*
X721482Y92044D01*
X722149Y91644D01*
X722749Y91511D01*
Y94311D01*
G01X721082Y96244D02*
X720616Y96711D01*
X720349Y97111D01*
X720216Y97644D01*
X720349Y98111D01*
X720616Y98444D01*
X721016Y98711D01*
X721482Y98778D01*
X721882Y98711D01*
X722282Y98444D01*
X722616Y98044D01*
X722749Y97578D01*
X722616Y97044D01*
X722216Y96578D01*
X721616Y96311D01*
X720949Y96244D01*
X720082Y96378D01*
X719616Y96578D01*
X719149Y96911D01*
X718816Y97378D01*
X718749Y97844D01*
X718882Y98311D01*
X719216Y98644D01*
G01X722749Y188021D02*
X718749D01*
X719549Y187221D01*
G01X722749D02*
Y188821D01*
G01Y192621D02*
X722682Y193088D01*
X722482Y193621D01*
X722149Y193954D01*
X721682Y194088D01*
X721216Y193954D01*
X720816Y193554D01*
X720616Y192954D01*
Y192288D01*
X720482Y191888D01*
X720149Y191554D01*
X719682Y191421D01*
X719216Y191621D01*
X718882Y192088D01*
X718749Y192621D01*
X718882Y193154D01*
X719216Y193621D01*
X719682Y193821D01*
X720149Y193688D01*
X720482Y193354D01*
X720616Y192954D01*
Y192288D01*
X720816Y191688D01*
X721216Y191288D01*
X721682Y191154D01*
X722149Y191288D01*
X722482Y191621D01*
X722682Y192154D01*
X722749Y192621D01*
G01X722282Y196088D02*
X722616Y196554D01*
X722749Y197088D01*
X722616Y197621D01*
X722216Y198088D01*
X721616Y198421D01*
X721016Y198554D01*
X720282D01*
X719682Y198421D01*
X719149Y198088D01*
X718882Y197688D01*
X718749Y197221D01*
X718882Y196688D01*
X719149Y196288D01*
X719549Y196021D01*
X720082Y195888D01*
X720549Y196021D01*
X721016Y196354D01*
X721282Y196754D01*
X721349Y197221D01*
X721216Y197754D01*
X720882Y198154D01*
X720282Y198554D01*
G01X722749Y200421D02*
X718749Y203221D01*
G01Y200421D02*
X722749Y203221D01*
G01Y206421D02*
X718749D01*
X719549Y205621D01*
G01X722749D02*
Y207221D01*
G01X719416Y209754D02*
X719016Y210154D01*
X718816Y210621D01*
X718749Y211154D01*
X718882Y211821D01*
X719216Y212288D01*
X719616Y212421D01*
X720016Y212354D01*
X720349Y212088D01*
X721016Y210754D01*
X721482Y210154D01*
X722149Y209754D01*
X722749Y209621D01*
Y212421D01*
G01X721082Y214354D02*
X720616Y214821D01*
X720349Y215221D01*
X720216Y215754D01*
X720349Y216221D01*
X720616Y216554D01*
X721016Y216821D01*
X721482Y216888D01*
X721882Y216821D01*
X722282Y216554D01*
X722616Y216154D01*
X722749Y215688D01*
X722616Y215154D01*
X722216Y214688D01*
X721616Y214421D01*
X720949Y214354D01*
X720082Y214488D01*
X719616Y214688D01*
X719149Y215021D01*
X718816Y215488D01*
X718749Y215954D01*
X718882Y216421D01*
X719216Y216754D01*
G01X821174Y69911D02*
X817174D01*
X817974Y69111D01*
G01X821174D02*
Y70711D01*
G01Y74511D02*
X821107Y74978D01*
X820907Y75511D01*
X820574Y75844D01*
X820107Y75978D01*
X819641Y75844D01*
X819241Y75444D01*
X819041Y74844D01*
Y74178D01*
X818907Y73778D01*
X818574Y73444D01*
X818107Y73311D01*
X817641Y73511D01*
X817307Y73978D01*
X817174Y74511D01*
X817307Y75044D01*
X817641Y75511D01*
X818107Y75711D01*
X818574Y75578D01*
X818907Y75244D01*
X819041Y74844D01*
Y74178D01*
X819241Y73578D01*
X819641Y73178D01*
X820107Y73044D01*
X820574Y73178D01*
X820907Y73511D01*
X821107Y74044D01*
X821174Y74511D01*
G01X820707Y77978D02*
X821041Y78444D01*
X821174Y78978D01*
X821041Y79511D01*
X820641Y79978D01*
X820041Y80311D01*
X819441Y80444D01*
X818707D01*
X818107Y80311D01*
X817574Y79978D01*
X817307Y79578D01*
X817174Y79111D01*
X817307Y78578D01*
X817574Y78178D01*
X817974Y77911D01*
X818507Y77778D01*
X818974Y77911D01*
X819441Y78244D01*
X819707Y78644D01*
X819774Y79111D01*
X819641Y79644D01*
X819307Y80044D01*
X818707Y80444D01*
G01X821174Y82311D02*
X817174Y85111D01*
G01Y82311D02*
X821174Y85111D01*
G01Y88311D02*
X817174D01*
X817974Y87511D01*
G01X821174D02*
Y89111D01*
G01X817841Y91644D02*
X817441Y92044D01*
X817241Y92511D01*
X817174Y93044D01*
X817307Y93711D01*
X817641Y94178D01*
X818041Y94311D01*
X818441Y94244D01*
X818774Y93978D01*
X819441Y92644D01*
X819907Y92044D01*
X820574Y91644D01*
X821174Y91511D01*
Y94311D01*
G01X819507Y96244D02*
X819041Y96711D01*
X818774Y97111D01*
X818641Y97644D01*
X818774Y98111D01*
X819041Y98444D01*
X819441Y98711D01*
X819907Y98778D01*
X820307Y98711D01*
X820707Y98444D01*
X821041Y98044D01*
X821174Y97578D01*
X821041Y97044D01*
X820641Y96578D01*
X820041Y96311D01*
X819374Y96244D01*
X818507Y96378D01*
X818041Y96578D01*
X817574Y96911D01*
X817241Y97378D01*
X817174Y97844D01*
X817307Y98311D01*
X817641Y98644D01*
G01X821174Y188022D02*
X817174D01*
X817974Y187222D01*
G01X821174D02*
Y188822D01*
G01Y192622D02*
X821107Y193089D01*
X820907Y193622D01*
X820574Y193955D01*
X820107Y194089D01*
X819641Y193955D01*
X819241Y193555D01*
X819041Y192955D01*
Y192289D01*
X818907Y191889D01*
X818574Y191555D01*
X818107Y191422D01*
X817641Y191622D01*
X817307Y192089D01*
X817174Y192622D01*
X817307Y193155D01*
X817641Y193622D01*
X818107Y193822D01*
X818574Y193689D01*
X818907Y193355D01*
X819041Y192955D01*
Y192289D01*
X819241Y191689D01*
X819641Y191289D01*
X820107Y191155D01*
X820574Y191289D01*
X820907Y191622D01*
X821107Y192155D01*
X821174Y192622D01*
G01X820707Y196089D02*
X821041Y196555D01*
X821174Y197089D01*
X821041Y197622D01*
X820641Y198089D01*
X820041Y198422D01*
X819441Y198555D01*
X818707D01*
X818107Y198422D01*
X817574Y198089D01*
X817307Y197689D01*
X817174Y197222D01*
X817307Y196689D01*
X817574Y196289D01*
X817974Y196022D01*
X818507Y195889D01*
X818974Y196022D01*
X819441Y196355D01*
X819707Y196755D01*
X819774Y197222D01*
X819641Y197755D01*
X819307Y198155D01*
X818707Y198555D01*
G01X821174Y200422D02*
X817174Y203222D01*
G01Y200422D02*
X821174Y203222D01*
G01Y206422D02*
X817174D01*
X817974Y205622D01*
G01X821174D02*
Y207222D01*
G01X817841Y209755D02*
X817441Y210155D01*
X817241Y210622D01*
X817174Y211155D01*
X817307Y211822D01*
X817641Y212289D01*
X818041Y212422D01*
X818441Y212355D01*
X818774Y212089D01*
X819441Y210755D01*
X819907Y210155D01*
X820574Y209755D01*
X821174Y209622D01*
Y212422D01*
G01X819507Y214355D02*
X819041Y214822D01*
X818774Y215222D01*
X818641Y215755D01*
X818774Y216222D01*
X819041Y216555D01*
X819441Y216822D01*
X819907Y216889D01*
X820307Y216822D01*
X820707Y216555D01*
X821041Y216155D01*
X821174Y215689D01*
X821041Y215155D01*
X820641Y214689D01*
X820041Y214422D01*
X819374Y214355D01*
X818507Y214489D01*
X818041Y214689D01*
X817574Y215022D01*
X817241Y215489D01*
X817174Y215955D01*
X817307Y216422D01*
X817641Y216755D01*
G01X842520Y629921D02*
G03X846457Y633858I0J3937D01*
G01Y759843D02*
Y633858D01*
G01X838583Y637796D02*
Y709449D01*
G01X850394Y763780D02*
G03X846457Y759843I0J-3937D01*
G01X903079Y763780D02*
X850394D01*
G01X812123Y734367D02*
G03I-4292J0D01*
G01X838583Y759843D02*
G03X834646Y763780I-3937J0D01*
G01X838583Y740158D02*
G03X846457I3937J0D01*
G01Y709449D02*
G03X838583I-3937J0D01*
G01Y740158D02*
Y759843D01*
G01X921260Y0D02*
G03X925197Y3937I0J3937D01*
G01D02*
Y723480D01*
G01X906600Y761603D02*
G03X903079Y763780I-3522J-1760D01*
G01X924781Y725241D02*
X906600Y761603D01*
G01X925197Y723480D02*
G03X924781Y725241I-3937J0D01*
G54D19*
X138970Y632277D03*
X128700Y615500D03*
X138700Y636655D03*
X113672Y605134D03*
X113512Y613401D03*
X113426Y609234D03*
X108137Y615870D03*
X113400Y621400D03*
X133835Y609620D03*
X179100Y455800D03*
X194411Y485447D03*
X193400Y463300D03*
X167680Y510640D03*
X183750Y524200D03*
X176900Y496500D03*
X190929Y512592D03*
X197611Y630698D03*
X193400Y630600D03*
X148210Y629830D03*
X150849Y710215D03*
X240900Y440900D03*
X236400Y440800D03*
X260513Y564135D03*
X277600Y680200D03*
X293326Y494174D03*
X288000Y561000D03*
X336881Y530496D03*
X336953Y534506D03*
X387500Y458200D03*
X378200Y476600D03*
X390769Y495379D03*
X384500Y616500D03*
X383313Y621780D03*
X366500Y586300D03*
X395127Y568056D03*
X395100Y572899D03*
X364600Y670800D03*
X479040Y47134D03*
X531050Y46998D03*
X864992Y175435D03*
X861420Y367269D03*
X1105450Y810525D03*
G54D28*
X421653Y126378D03*
X428740Y121654D03*
X421653Y130709D03*
X428740Y125985D03*
X421653Y136221D03*
X428740Y131496D03*
Y135827D03*
X421653Y183071D03*
Y140551D03*
Y144882D03*
X428740Y140158D03*
X421653Y150394D03*
X428740Y145670D03*
X421653Y154725D03*
X428740Y150000D03*
X421653Y159055D03*
X428740Y154331D03*
X421653Y164567D03*
X428740Y159843D03*
X421653Y168898D03*
X428740Y164173D03*
X421653Y173229D03*
X428740Y168504D03*
X421653Y178740D03*
X428740Y174016D03*
X435827Y126378D03*
X450000D03*
X464173D03*
X442913Y121654D03*
X457086D03*
X471260D03*
X435827Y130709D03*
X442913Y125985D03*
X450000Y130709D03*
X457086Y125985D03*
X464173Y130709D03*
X471260Y125985D03*
X435827Y136221D03*
X442913Y131496D03*
X450000Y136221D03*
X457086Y131496D03*
X464173Y136221D03*
X471260Y131496D03*
X442913Y135827D03*
X457086D03*
X471260D03*
X435827Y183071D03*
X450000D03*
X464173D03*
X435827Y140551D03*
X450000D03*
X464173D03*
X435827Y144882D03*
X442913Y140158D03*
X450000Y144882D03*
X457086Y140158D03*
X464173Y144882D03*
X471260Y140158D03*
X435827Y150394D03*
X442913Y145670D03*
X450000Y150394D03*
X457086Y145670D03*
X464173Y150394D03*
X471260Y145670D03*
X435827Y154725D03*
X442913Y150000D03*
X450000Y154725D03*
X457086Y150000D03*
X464173Y154725D03*
X471260Y150000D03*
X435827Y159055D03*
X442913Y154331D03*
X450000Y159055D03*
X457086Y154331D03*
X464173Y159055D03*
X471260Y154331D03*
X435827Y164567D03*
X442913Y159843D03*
X450000Y164567D03*
X457086Y159843D03*
X464173Y164567D03*
X471260Y159843D03*
X435827Y168898D03*
X442913Y164173D03*
X450000Y168898D03*
X457086Y164173D03*
X464173Y168898D03*
X471260Y164173D03*
X435827Y173229D03*
X442913Y168504D03*
X450000Y173229D03*
X457086Y168504D03*
X464173Y173229D03*
X471260Y168504D03*
X435827Y178740D03*
X442913Y174016D03*
X450000Y178740D03*
X457086Y174016D03*
X464173Y178740D03*
X471260Y174016D03*
X506693Y126378D03*
X520866D03*
X535039D03*
X549212D03*
X513779Y121654D03*
X527953D03*
X542126D03*
X556299D03*
X506693Y130709D03*
X513779Y125985D03*
X520866Y130709D03*
X527953Y125985D03*
X535039Y130709D03*
X542126Y125985D03*
X549212Y130709D03*
X556299Y125985D03*
X506693Y136221D03*
X513779Y131496D03*
X520866Y136221D03*
X527953Y131496D03*
X535039Y136221D03*
X542126Y131496D03*
X549212Y136221D03*
X556299Y131496D03*
X513779Y135827D03*
X527953D03*
X542126D03*
X556299D03*
X506693Y183071D03*
X520866D03*
X535039D03*
X549212D03*
X506693Y140551D03*
X520866D03*
X535039D03*
X549212D03*
X506693Y144882D03*
X513779Y140158D03*
X520866Y144882D03*
X527953Y140158D03*
X535039Y144882D03*
X542126Y140158D03*
X549212Y144882D03*
X556299Y140158D03*
X506693Y150394D03*
X513779Y145670D03*
X520866Y150394D03*
X527953Y145670D03*
X535039Y150394D03*
X542126Y145670D03*
X549212Y150394D03*
X556299Y145670D03*
X506693Y154725D03*
X513779Y150000D03*
X520866Y154725D03*
X527953Y150000D03*
X535039Y154725D03*
X542126Y150000D03*
X549212Y154725D03*
X556299Y150000D03*
X506693Y159055D03*
X513779Y154331D03*
X520866Y159055D03*
X527953Y154331D03*
X535039Y159055D03*
X542126Y154331D03*
X549212Y159055D03*
X556299Y154331D03*
X506693Y164567D03*
X513779Y159843D03*
X520866Y164567D03*
X527953Y159843D03*
X535039Y164567D03*
X542126Y159843D03*
X549212Y164567D03*
X556299Y159843D03*
X506693Y168898D03*
X513779Y164173D03*
X520866Y168898D03*
X527953Y164173D03*
X535039Y168898D03*
X542126Y164173D03*
X549212Y168898D03*
X556299Y164173D03*
X506693Y173229D03*
X513779Y168504D03*
X520866Y173229D03*
X527953Y168504D03*
X535039Y173229D03*
X542126Y168504D03*
X549212Y173229D03*
X556299Y168504D03*
X506693Y178740D03*
X513779Y174016D03*
X520866Y178740D03*
X527953Y174016D03*
X535039Y178740D03*
X542126Y174016D03*
X549212Y178740D03*
X556299Y174016D03*
X1105450Y725475D03*
G54D29*
X428740Y179528D03*
X457086D03*
X442913D03*
X471260D03*
X513779D03*
X527953D03*
X542126D03*
X556299D03*
X1105450Y753825D03*
M02*
